FILE_TYPE = MACRO_DRAWING;
SET COLOR_WIRE YELLOW;
SET COLOR_PROP MONO;
SET COLOR_DOT WHITE;
SET COLOR_ARC YELLOW;
SET COLOR_BODY GREEN;
SET COLOR_NOTE MONO;
SET PROP_DISPLAY VALUE;
SET PAGE_NUMBER P154;
FORCEADD TTL1G32_A..1
(-2275 1150);
FORCEPROP 2 LASTPIN (-2125 1150) $PN 4
J 0
(-2115 1160);
DISPLAY 0.617021 (-2115 1160);
PAINT ORANGE (-2115 1160);
FORCEPROP 1 LAST MATERIAL IC
J 0
(-2375 1325);
DISPLAY 0.617021 (-2375 1325);
PAINT SKYBLUE (-2375 1325);
FORCEPROP 1 LAST LOCATION U2T2
J 0
(-2375 1375);
DISPLAY 0.617021 (-2375 1375);
PAINT AQUA (-2375 1375);
FORCEPROP 2 LASTPIN (-2425 1200) $PN 1
J 2
(-2435 1210);
DISPLAY 0.617021 (-2435 1210);
PAINT ORANGE (-2435 1210);
FORCEPROP 2 LASTPIN (-2425 1100) $PN 2
J 2
(-2435 1110);
DISPLAY 0.617021 (-2435 1110);
PAINT ORANGE (-2435 1110);
FORCEPROP 1 LAST VALUE 74LVC1G32
J 0
(-2375 1275);
DISPLAY 0.617021 (-2375 1275);
PAINT SKYBLUE (-2375 1275);
FORCEPROP 1 LAST POWER_GROUP VCC=P3V3_STBY;GND=GND
J 0
(-2375 950);
DISPLAY 0.617021 (-2375 950);
PAINT ORANGE (-2375 950);
FORCEPROP 1 LAST PART_NUMBER E60229-001
J 0
(-2375 1000);
DISPLAY 0.617021 (-2375 1000);
PAINT BLUE (-2375 1000);
FORCEPROP 0 LAST GROUP NI_BIOS_ROM2
J 0
(-2382 899);
DISPLAY 0.638298 (-2382 899);
PAINT BROWN (-2382 899);
DISPLAY BOTH (-2382 899);
FORCEPROP 2 LAST ROOM SB_BMC_SPI_MUX
J 0
(-2375 1425);
DISPLAY 1.021277 (-2375 1425);
PAINT ORANGE (-2375 1425);
DISPLAY INVISIBLE (-2375 1425);
FORCEPROP 1 LAST PATH I100
J 0
(-1925 1325);
DISPLAY 0.978723 (-1925 1325);
PAINT ORANGE (-1925 1325);
DISPLAY INVISIBLE (-1925 1325);
FORCEPROP 2 LAST CDS_LOCATION U2T2
J 0
(-2375 1375);
DISPLAY 0.617021 (-2375 1375);
PAINT AQUA (-2375 1375);
DISPLAY INVISIBLE (-2375 1375);
FORCEPROP 2 LAST SEC 1
J 0
(-2375 1425);
DISPLAY 0.680851 (-2375 1425);
PAINT MONO (-2375 1425);
DISPLAY INVISIBLE (-2375 1425);
FORCEPROP 2 LAST BOM_COST MIO_BIOS_MEM
J 0
(-2375 1475);
DISPLAY 1.021277 (-2375 1475);
PAINT ORANGE (-2375 1475);
DISPLAY INVISIBLE (-2375 1475);
FORCEPROP 2 LAST SEC_TYPE SOT
J 0
(-2375 1425);
DISPLAY 1.021277 (-2375 1425);
PAINT ORANGE (-2375 1425);
DISPLAY INVISIBLE (-2375 1425);
FORCEPROP 2 LAST CDS_LIB mstr_ttl
J 0
(-2275 1150);
PAINT ORANGE (-2275 1150);
DISPLAY INVISIBLE (-2275 1150);
FORCEPROP 1 LAST PACK_TYPE SOT
J 0
(-2375 1425);
DISPLAY 0.978723 (-2375 1425);
PAINT SKYBLUE (-2375 1425);
DISPLAY INVISIBLE (-2375 1425);
FORCEADD RES..1
(-1450 1875);
FORCEPROP 1 LAST PACK_TYPE 0402
J 0
(-1225 1825);
DISPLAY 0.617021 (-1225 1825);
PAINT SKYBLUE (-1225 1825);
FORCEPROP 1 LASTPIN (-1550 1875) $PN 1
J 0
(-1538 1887);
DISPLAY 0.617021 (-1538 1887);
PAINT ORANGE (-1538 1887);
FORCEPROP 1 LAST MATERIAL CHIP
J 0
(-1325 1825);
DISPLAY 0.617021 (-1325 1825);
PAINT SKYBLUE (-1325 1825);
FORCEPROP 1 LASTPIN (-1350 1875) $PN 2
J 0
(-1388 1887);
DISPLAY 0.617021 (-1388 1887);
PAINT ORANGE (-1388 1887);
FORCEPROP 1 LAST TOLERANCE 1%
J 0
(-1675 1825);
DISPLAY 0.617021 (-1675 1825);
PAINT SKYBLUE (-1675 1825);
FORCEPROP 1 LAST LOCATION R2T13
J 0
(-1450 1925);
DISPLAY 0.617021 (-1450 1925);
PAINT AQUA (-1450 1925);
FORCEPROP 1 LAST WATTAGE 1/16W
J 2
(-1350 1825);
DISPLAY 0.617021 (-1350 1825);
PAINT SKYBLUE (-1350 1825);
FORCEPROP 1 LAST PART_NUMBER G21796-004
J 0
(-1550 1775);
DISPLAY 0.617021 (-1550 1775);
PAINT BLUE (-1550 1775);
FORCEPROP 1 LAST VALUE 200.0
J 2
(-1500 1825);
DISPLAY 0.617021 (-1500 1825);
PAINT SKYBLUE (-1500 1825);
FORCEPROP 0 LAST GROUP NI_BIOS_ROM2
J 0
(-1557 1724);
DISPLAY 0.638298 (-1557 1724);
PAINT BROWN (-1557 1724);
DISPLAY BOTH (-1557 1724);
FORCEPROP 2 LAST ROOM SB_BMC_SPI_MUX
J 0
(-1450 1975);
DISPLAY 1.021277 (-1450 1975);
PAINT ORANGE (-1450 1975);
DISPLAY INVISIBLE (-1450 1975);
FORCEPROP 1 LAST PATH I101
J 0
(-1500 2025);
DISPLAY 0.978723 (-1500 2025);
PAINT WHITE (-1500 2025);
DISPLAY INVISIBLE (-1500 2025);
FORCEPROP 2 LAST CDS_LOCATION R2T13
J 0
(-1450 1925);
DISPLAY 0.617021 (-1450 1925);
PAINT AQUA (-1450 1925);
DISPLAY INVISIBLE (-1450 1925);
FORCEPROP 2 LAST SEC 1
J 0
(-1500 2075);
DISPLAY 0.680851 (-1500 2075);
PAINT MONO (-1500 2075);
DISPLAY INVISIBLE (-1500 2075);
FORCEPROP 2 LAST BOM_COST MIO_BIOS_MEM
J 0
(-1450 2025);
DISPLAY 1.021277 (-1450 2025);
PAINT ORANGE (-1450 2025);
DISPLAY INVISIBLE (-1450 2025);
FORCEPROP 2 LAST CDS_LIB mstr_discrete
J 0
(-1450 1875);
PAINT ORANGE (-1450 1875);
DISPLAY INVISIBLE (-1450 1875);
FORCEPROP 2 LAST SEC_TYPE 0402
J 0
(-1500 2075);
DISPLAY 1.021277 (-1500 2075);
PAINT ORANGE (-1500 2075);
DISPLAY INVISIBLE (-1500 2075);
FORCEADD OFFPAGE..2
(-825 1875);
FORCEPROP 2 LAST $XR0 153 
J 0
(-636 1875);
DISPLAY 0.638298 (-636 1875);
PAINT MONO (-636 1875);
FORCEPROP 1 LAST COMMENT_BODY TRUE
J 0
(-870 1780);
DISPLAY 0.872340 (-870 1780);
PAINT GREEN (-870 1780);
DISPLAY INVISIBLE (-870 1780);
FORCEPROP 1 LAST OFFPAGE TRUE
J 0
(-500 1750);
DISPLAY 0.872340 (-500 1750);
PAINT GREEN (-500 1750);
DISPLAY INVISIBLE (-500 1750);
FORCEPROP 2 LAST PATH I102
J 0
(-775 1950);
DISPLAY 1.021277 (-775 1950);
PAINT ORANGE (-775 1950);
DISPLAY INVISIBLE (-775 1950);
FORCEPROP 2 LAST CDS_LIB mstr_standard
J 0
(-825 1875);
PAINT ORANGE (-825 1875);
DISPLAY INVISIBLE (-825 1875);
FORCEADD OFFPAGE..2
(-600 1150);
FORCEPROP 2 LAST $XR0 153 
J 0
(-411 1150);
DISPLAY 0.638298 (-411 1150);
PAINT MONO (-411 1150);
FORCEPROP 1 LAST COMMENT_BODY TRUE
J 0
(-645 1055);
DISPLAY 0.872340 (-645 1055);
PAINT GREEN (-645 1055);
DISPLAY INVISIBLE (-645 1055);
FORCEPROP 1 LAST OFFPAGE TRUE
J 0
(-275 1025);
DISPLAY 0.872340 (-275 1025);
PAINT GREEN (-275 1025);
DISPLAY INVISIBLE (-275 1025);
FORCEPROP 2 LAST PATH I103
J 0
(-550 1225);
DISPLAY 1.021277 (-550 1225);
PAINT ORANGE (-550 1225);
DISPLAY INVISIBLE (-550 1225);
FORCEPROP 2 LAST CDS_LIB mstr_standard
J 0
(-600 1150);
PAINT ORANGE (-600 1150);
DISPLAY INVISIBLE (-600 1150);
FORCEADD RES..2
(-3100 2200);
FORCEPROP 1 LASTPIN (-3100 2100) $PN 2
J 0
(-3095 2110);
DISPLAY 0.617021 (-3095 2110);
PAINT ORANGE (-3095 2110);
FORCEPROP 1 LAST VALUE 4.75K
J 0
(-3055 2275);
DISPLAY 0.617021 (-3055 2275);
PAINT SKYBLUE (-3055 2275);
FORCEPROP 1 LAST LOCATION R2T11
J 0
(-3055 2325);
DISPLAY 0.617021 (-3055 2325);
PAINT AQUA (-3055 2325);
FORCEPROP 1 LAST MATERIAL CHIP
J 0
(-3060 2125);
DISPLAY 0.617021 (-3060 2125);
PAINT SKYBLUE (-3060 2125);
FORCEPROP 1 LAST WATTAGE 1/16W
J 0
(-3060 2175);
DISPLAY 0.617021 (-3060 2175);
PAINT SKYBLUE (-3060 2175);
FORCEPROP 1 LAST TOLERANCE 1%
J 0
(-3055 2225);
DISPLAY 0.617021 (-3055 2225);
PAINT SKYBLUE (-3055 2225);
FORCEPROP 1 LASTPIN (-3100 2300) $PN 1
J 0
(-3095 2262);
DISPLAY 0.617021 (-3095 2262);
PAINT ORANGE (-3095 2262);
FORCEPROP 1 LAST PART_NUMBER G21796-072
J 0
(-3060 2075);
DISPLAY 0.617021 (-3060 2075);
PAINT BLUE (-3060 2075);
FORCEPROP 1 LAST PACK_TYPE 0402
J 0
(-3060 2025);
DISPLAY 0.617021 (-3060 2025);
PAINT SKYBLUE (-3060 2025);
FORCEPROP 0 LAST GROUP NI_BIOS_ROM2
J 0
(-2857 2324);
DISPLAY 0.638298 (-2857 2324);
PAINT BROWN (-2857 2324);
DISPLAY BOTH (-2857 2324);
FORCEPROP 2 LAST ROOM SB_BMC_SPI_MUX
J 0
(-3050 2375);
DISPLAY 1.021277 (-3050 2375);
PAINT ORANGE (-3050 2375);
DISPLAY INVISIBLE (-3050 2375);
FORCEPROP 1 LAST PATH I105
J 0
(-3050 2375);
DISPLAY 0.978723 (-3050 2375);
PAINT WHITE (-3050 2375);
DISPLAY INVISIBLE (-3050 2375);
FORCEPROP 2 LAST CDS_LOCATION R2T11
J 0
(-3055 2325);
DISPLAY 0.617021 (-3055 2325);
PAINT AQUA (-3055 2325);
DISPLAY INVISIBLE (-3055 2325);
FORCEPROP 2 LAST SEC 1
J 0
(-3050 2425);
PAINT MONO (-3050 2425);
DISPLAY INVISIBLE (-3050 2425);
FORCEPROP 2 LAST BOM_COST MIO_BIOS_MEM
J 0
(-3050 2425);
DISPLAY 1.021277 (-3050 2425);
PAINT ORANGE (-3050 2425);
DISPLAY INVISIBLE (-3050 2425);
FORCEPROP 2 LAST SEC_TYPE 0402
J 0
(-3050 2425);
DISPLAY 1.021277 (-3050 2425);
PAINT ORANGE (-3050 2425);
DISPLAY INVISIBLE (-3050 2425);
FORCEPROP 2 LAST CDS_LIB mstr_discrete
J 0
(-3100 2200);
PAINT ORANGE (-3100 2200);
DISPLAY INVISIBLE (-3100 2200);
FORCEADD RES..2
R 2
(-3775 1750);
FORCEPROP 1 LAST VALUE 10.0K
J 2
(-3820 1825);
DISPLAY 0.617021 (-3820 1825);
PAINT SKYBLUE (-3820 1825);
FORCEPROP 0 LAST GROUP NI_BIOS_ROM2
J 0
(-4082 1524);
DISPLAY 0.638298 (-4082 1524);
PAINT BROWN (-4082 1524);
DISPLAY BOTH (-4082 1524);
FORCEPROP 1 LAST LOCATION R2T8
J 2
(-3820 1875);
DISPLAY 0.617021 (-3820 1875);
PAINT AQUA (-3820 1875);
FORCEPROP 1 LAST WATTAGE 1/16W
J 2
(-3815 1725);
DISPLAY 0.617021 (-3815 1725);
PAINT SKYBLUE (-3815 1725);
FORCEPROP 1 LAST PART_NUMBER G21796-016
J 2
(-3815 1625);
DISPLAY 0.617021 (-3815 1625);
PAINT BLUE (-3815 1625);
FORCEPROP 1 LAST PACK_TYPE 0402
J 2
(-3815 1575);
DISPLAY 0.617021 (-3815 1575);
PAINT SKYBLUE (-3815 1575);
FORCEPROP 1 LASTPIN (-3775 1650) $PN 2
J 2
(-3780 1660);
DISPLAY 0.617021 (-3780 1660);
PAINT ORANGE (-3780 1660);
FORCEPROP 1 LAST MATERIAL CHIP
J 2
(-3815 1675);
DISPLAY 0.617021 (-3815 1675);
PAINT SKYBLUE (-3815 1675);
FORCEPROP 1 LAST TOLERANCE 1%
J 2
(-3820 1775);
DISPLAY 0.617021 (-3820 1775);
PAINT SKYBLUE (-3820 1775);
FORCEPROP 1 LASTPIN (-3775 1850) $PN 1
J 2
(-3780 1812);
DISPLAY 0.617021 (-3780 1812);
PAINT ORANGE (-3780 1812);
FORCEPROP 2 LAST ROOM SB_BMC_SPI_MUX
J 2
(-3825 1925);
DISPLAY 1.021277 (-3825 1925);
PAINT ORANGE (-3825 1925);
DISPLAY INVISIBLE (-3825 1925);
FORCEPROP 1 LAST PATH I106
J 2
(-3825 1925);
DISPLAY 0.978723 (-3825 1925);
PAINT WHITE (-3825 1925);
DISPLAY INVISIBLE (-3825 1925);
FORCEPROP 2 LAST CDS_LOCATION R2T8
J 2
(-3820 1875);
DISPLAY 0.617021 (-3820 1875);
PAINT AQUA (-3820 1875);
DISPLAY INVISIBLE (-3820 1875);
FORCEPROP 2 LAST SEC 1
J 2
(-3825 1975);
PAINT MONO (-3825 1975);
DISPLAY INVISIBLE (-3825 1975);
FORCEPROP 2 LAST BOM_COST MIO_BIOS_MEM
J 2
(-3825 1975);
DISPLAY 1.021277 (-3825 1975);
PAINT ORANGE (-3825 1975);
DISPLAY INVISIBLE (-3825 1975);
FORCEPROP 2 LAST SEC_TYPE 0402
J 2
(-3825 1975);
DISPLAY 1.021277 (-3825 1975);
PAINT ORANGE (-3825 1975);
DISPLAY INVISIBLE (-3825 1975);
FORCEPROP 2 LAST CDS_LIB mstr_discrete
J 2
(-3775 1750);
PAINT ORANGE (-3775 1750);
DISPLAY INVISIBLE (-3775 1750);
FORCEADD OFFPAGE..1
(-4475 1475);
FORCEPROP 2 LAST $XR1 147 
J 0
(-4877 1475);
DISPLAY 0.638298 (-4877 1475);
PAINT MONO (-4877 1475);
FORCEPROP 2 LAST $XR0 120 
J 0
(-4757 1475);
DISPLAY 0.638298 (-4757 1475);
PAINT MONO (-4757 1475);
FORCEPROP 1 LAST COMMENT_BODY TRUE
J 0
(-4350 1375);
DISPLAY 0.872340 (-4350 1375);
PAINT GREEN (-4350 1375);
DISPLAY INVISIBLE (-4350 1375);
FORCEPROP 1 LAST OFFPAGE TRUE
J 0
(-4150 1350);
DISPLAY 0.872340 (-4150 1350);
PAINT GREEN (-4150 1350);
DISPLAY INVISIBLE (-4150 1350);
FORCEPROP 2 LAST CDS_LIB mstr_standard
J 0
(-4475 1475);
PAINT ORANGE (-4475 1475);
DISPLAY INVISIBLE (-4475 1475);
FORCEPROP 2 LAST PATH I107
J 0
(-4425 1550);
DISPLAY 1.021277 (-4425 1550);
PAINT ORANGE (-4425 1550);
DISPLAY INVISIBLE (-4425 1550);
FORCEADD GND..1
(-3100 1275);
FORCEPROP 3 LASTPIN (-3100 1325) SIG_NAME GND\g
J 0
(-3090 1335);
DISPLAY 0.659574 (-3090 1335);
PAINT MONO (-3090 1335);
DISPLAY INVISIBLE (-3090 1335);
FORCEPROP 1 LAST HDL_POWER GND
J 0
(-3100 1425);
DISPLAY 0.872340 (-3100 1425);
PAINT GREEN (-3100 1425);
DISPLAY INVISIBLE (-3100 1425);
FORCEPROP 1 LAST BODY_TYPE PLUMBING
J 0
(-3145 1232);
DISPLAY 0.340426 (-3145 1232);
PAINT GREEN (-3145 1232);
DISPLAY INVISIBLE (-3145 1232);
FORCEPROP 1 LAST PATH I109
J 0
(-3025 1275);
DISPLAY 0.872340 (-3025 1275);
PAINT AQUA (-3025 1275);
DISPLAY INVISIBLE (-3025 1275);
FORCEPROP 1 LAST SIZE 1B
J 0
(-3025 1225);
DISPLAY 0.872340 (-3025 1225);
PAINT AQUA (-3025 1225);
DISPLAY INVISIBLE (-3025 1225);
FORCEPROP 2 LAST CDS_LIB mstr_symbols
J 0
(-3100 1275);
PAINT ORANGE (-3100 1275);
DISPLAY INVISIBLE (-3100 1275);
FORCEPROP 1 LAST VOLTAGE 0.0V
J 0
(-3145 1232);
DISPLAY 0.340426 (-3145 1232);
PAINT SKYBLUE (-3145 1232);
DISPLAY INVISIBLE (-3145 1232);
FORCEADD P3V3_STBY..1
(-3100 2450);
FORCEPROP 3 LASTPIN (-3100 2400) SIG_NAME P3V3_STBY\g
J 0
(-3090 2410);
DISPLAY 0.659574 (-3090 2410);
PAINT MONO (-3090 2410);
DISPLAY INVISIBLE (-3090 2410);
FORCEPROP 1 LAST HDL_POWER P3V3_STBY
J 0
(-3400 2325);
DISPLAY 0.872340 (-3400 2325);
PAINT ORANGE (-3400 2325);
DISPLAY INVISIBLE (-3400 2325);
FORCEPROP 1 LAST BODY_TYPE PLUMBING
J 0
(-3145 2407);
DISPLAY 0.340426 (-3145 2407);
PAINT GREEN (-3145 2407);
DISPLAY INVISIBLE (-3145 2407);
FORCEPROP 1 LAST PATH I110
J 0
(-3055 2452);
DISPLAY 0.340426 (-3055 2452);
PAINT GREEN (-3055 2452);
DISPLAY INVISIBLE (-3055 2452);
FORCEPROP 2 LAST CDS_LIB mstr_symbols
J 0
(-3100 2450);
PAINT ORANGE (-3100 2450);
DISPLAY INVISIBLE (-3100 2450);
FORCEPROP 1 LAST SIZE 1B
J 0
(-3055 2472);
DISPLAY 0.340426 (-3055 2472);
PAINT GREEN (-3055 2472);
DISPLAY INVISIBLE (-3055 2472);
FORCEPROP 1 LAST VOLTAGE 3.3V
J 0
(-3145 2407);
DISPLAY 0.340426 (-3145 2407);
PAINT SKYBLUE (-3145 2407);
DISPLAY INVISIBLE (-3145 2407);
FORCEADD P3V3_STBY..1
(-3775 2025);
FORCEPROP 3 LASTPIN (-3775 1975) SIG_NAME P3V3_STBY\g
J 0
(-3765 1985);
DISPLAY 0.659574 (-3765 1985);
PAINT MONO (-3765 1985);
DISPLAY INVISIBLE (-3765 1985);
FORCEPROP 1 LAST HDL_POWER P3V3_STBY
J 0
(-4075 1900);
DISPLAY 0.872340 (-4075 1900);
PAINT ORANGE (-4075 1900);
DISPLAY INVISIBLE (-4075 1900);
FORCEPROP 1 LAST BODY_TYPE PLUMBING
J 0
(-3820 1982);
DISPLAY 0.340426 (-3820 1982);
PAINT GREEN (-3820 1982);
DISPLAY INVISIBLE (-3820 1982);
FORCEPROP 1 LAST PATH I111
J 0
(-3730 2027);
DISPLAY 0.340426 (-3730 2027);
PAINT GREEN (-3730 2027);
DISPLAY INVISIBLE (-3730 2027);
FORCEPROP 2 LAST CDS_LIB mstr_symbols
J 0
(-3775 2025);
PAINT ORANGE (-3775 2025);
DISPLAY INVISIBLE (-3775 2025);
FORCEPROP 1 LAST SIZE 1B
J 0
(-3730 2047);
DISPLAY 0.340426 (-3730 2047);
PAINT GREEN (-3730 2047);
DISPLAY INVISIBLE (-3730 2047);
FORCEPROP 1 LAST VOLTAGE 3.3V
J 0
(-3820 1982);
DISPLAY 0.340426 (-3820 1982);
PAINT SKYBLUE (-3820 1982);
DISPLAY INVISIBLE (-3820 1982);
FORCEADD RES..1
(-6725 3600);
FORCEPROP 1 LAST VALUE 0.0
J 2
(-6750 3550);
DISPLAY 0.617021 (-6750 3550);
PAINT SKYBLUE (-6750 3550);
FORCEPROP 1 LAST MATERIAL CHIP
J 0
(-6575 3550);
DISPLAY 0.617021 (-6575 3550);
PAINT SKYBLUE (-6575 3550);
FORCEPROP 1 LAST LOCATION R8F6
J 0
(-6775 3650);
DISPLAY 0.617021 (-6775 3650);
PAINT AQUA (-6775 3650);
FORCEPROP 1 LAST TOLERANCE 5%
J 0
(-6650 3550);
DISPLAY 0.617021 (-6650 3550);
PAINT SKYBLUE (-6650 3550);
FORCEPROP 1 LAST PACK_TYPE 0402
J 0
(-6475 3550);
DISPLAY 0.617021 (-6475 3550);
PAINT SKYBLUE (-6475 3550);
FORCEPROP 1 LASTPIN (-6625 3600) $PN 2
J 0
(-6663 3612);
DISPLAY 0.617021 (-6663 3612);
PAINT MONO (-6663 3612);
FORCEPROP 1 LASTPIN (-6825 3600) $PN 1
J 0
(-6813 3612);
DISPLAY 0.617021 (-6813 3612);
PAINT MONO (-6813 3612);
FORCEPROP 1 LAST WATTAGE 1/16W
J 2
(-6850 3550);
DISPLAY 0.617021 (-6850 3550);
PAINT SKYBLUE (-6850 3550);
FORCEPROP 1 LAST PART_NUMBER G21497-005
J 0
(-6850 3500);
DISPLAY 0.617021 (-6850 3500);
PAINT BLUE (-6850 3500);
FORCEPROP 1 LAST PATH I119
J 0
(-6775 3750);
DISPLAY 0.978723 (-6775 3750);
PAINT WHITE (-6775 3750);
DISPLAY INVISIBLE (-6775 3750);
FORCEPROP 2 LAST CDS_LIB mstr_discrete
J 0
(-6725 3600);
PAINT RED (-6725 3600);
DISPLAY INVISIBLE (-6725 3600);
FORCEPROP 2 LAST CDS_SEC 1
J 0
(-6775 3800);
DISPLAY 1.404255 (-6775 3800);
PAINT ORANGE (-6775 3800);
DISPLAY INVISIBLE (-6775 3800);
FORCEPROP 2 LAST $SEC 1
J 0
(-6775 3800);
DISPLAY 0.936170 (-6775 3800);
PAINT MONO (-6775 3800);
DISPLAY INVISIBLE (-6775 3800);
FORCEPROP 2 LAST CDS_LOCATION R8F6
J 0
(-6775 3650);
DISPLAY 0.617021 (-6775 3650);
PAINT AQUA (-6775 3650);
DISPLAY INVISIBLE (-6775 3650);
FORCEPROP 2 LAST ROOM MIO_BIOS_MEM
J 0
(-6775 3740);
DISPLAY 0.787234 (-6775 3740);
PAINT SKYBLUE (-6775 3740);
DISPLAY INVISIBLE (-6775 3740);
FORCEADD P3V3_STBY..1
(-5575 4600);
FORCEPROP 3 LASTPIN (-5575 4550) SIG_NAME P3V3_STBY\g
J 0
(-5565 4560);
DISPLAY 0.659574 (-5565 4560);
PAINT MONO (-5565 4560);
DISPLAY INVISIBLE (-5565 4560);
FORCEPROP 1 LAST HDL_POWER P3V3_STBY
J 0
(-5875 4475);
DISPLAY 0.872340 (-5875 4475);
PAINT ORANGE (-5875 4475);
DISPLAY INVISIBLE (-5875 4475);
FORCEPROP 1 LAST BODY_TYPE PLUMBING
J 0
(-5620 4557);
DISPLAY 0.340426 (-5620 4557);
PAINT GREEN (-5620 4557);
DISPLAY INVISIBLE (-5620 4557);
FORCEPROP 1 LAST PATH I12
J 0
(-5530 4602);
DISPLAY 0.340426 (-5530 4602);
PAINT GREEN (-5530 4602);
DISPLAY INVISIBLE (-5530 4602);
FORCEPROP 1 LAST SIZE 1B
J 0
(-5530 4622);
DISPLAY 0.340426 (-5530 4622);
PAINT GREEN (-5530 4622);
DISPLAY INVISIBLE (-5530 4622);
FORCEPROP 2 LAST CDS_LIB mstr_symbols
J 0
(-5575 4600);
PAINT ORANGE (-5575 4600);
DISPLAY INVISIBLE (-5575 4600);
FORCEPROP 1 LAST VOLTAGE 3.3V
J 0
(-5620 4557);
DISPLAY 0.340426 (-5620 4557);
PAINT SKYBLUE (-5620 4557);
DISPLAY INVISIBLE (-5620 4557);
FORCEADD OFFPAGE..2
R 2
(-7325 3600);
FORCEPROP 2 LAST $XR1 121 
J 0
(-7700 3600);
DISPLAY 0.638298 (-7700 3600);
PAINT MONO (-7700 3600);
FORCEPROP 2 LAST $XR0 184 
J 0
(-7580 3600);
DISPLAY 0.638298 (-7580 3600);
PAINT MONO (-7580 3600);
FORCEPROP 1 LAST COMMENT_BODY TRUE
J 2
(-7280 3505);
DISPLAY 1.404255 (-7280 3505);
PAINT GREEN (-7280 3505);
DISPLAY INVISIBLE (-7280 3505);
FORCEPROP 1 LAST OFFPAGE TRUE
J 2
(-7650 3475);
PAINT GREEN (-7650 3475);
DISPLAY INVISIBLE (-7650 3475);
FORCEPROP 2 LAST PATH I123
J 0
(-7600 3650);
DISPLAY 1.021277 (-7600 3650);
PAINT ORANGE (-7600 3650);
DISPLAY INVISIBLE (-7600 3650);
FORCEPROP 2 LAST CDS_LIB mstr_standard
J 2
(-7325 3600);
PAINT ORANGE (-7325 3600);
DISPLAY INVISIBLE (-7325 3600);
FORCEADD FET_N..8
(-3100 1575);
FORCEPROP 0 LAST GROUP NI_BIOS_ROM2
J 0
(-2907 1374);
DISPLAY 0.638298 (-2907 1374);
PAINT BROWN (-2907 1374);
DISPLAY BOTH (-2907 1374);
FORCEPROP 1 LAST MATERIAL FET
J 0
(-2900 1475);
DISPLAY 0.617021 (-2900 1475);
PAINT SKYBLUE (-2900 1475);
FORCEPROP 1 LASTPIN (-3300 1475) $PN 1
J 2
(-3297 1490);
DISPLAY 0.617021 (-3297 1490);
PAINT WHITE (-3297 1490);
FORCEPROP 1 LASTPIN (-3100 1375) $PN 2
J 2
(-3042 1375);
DISPLAY 0.617021 (-3042 1375);
PAINT WHITE (-3042 1375);
FORCEPROP 1 LAST VALUE 2N7002
J 0
(-2900 1525);
DISPLAY 0.617021 (-2900 1525);
PAINT SKYBLUE (-2900 1525);
FORCEPROP 1 LASTPIN (-3100 1775) $PN 3
J 2
(-3047 1740);
DISPLAY 0.617021 (-3047 1740);
PAINT WHITE (-3047 1740);
FORCEPROP 1 LAST LOCATION Q8F1
J 0
(-2900 1575);
DISPLAY 0.617021 (-2900 1575);
PAINT AQUA (-2900 1575);
FORCEPROP 1 LAST PART_NUMBER C79254-001
J 0
(-2900 1425);
DISPLAY 0.617021 (-2900 1425);
PAINT BLUE (-2900 1425);
FORCEPROP 0 LAST ROOM SB_BMC_SPI_MUX
J 0
(-2900 1675);
DISPLAY 1.021277 (-2900 1675);
PAINT ORANGE (-2900 1675);
DISPLAY INVISIBLE (-2900 1675);
FORCEPROP 1 LAST PATH I126
J 0
(-2900 1625);
DISPLAY 0.978723 (-2900 1625);
PAINT BLUE (-2900 1625);
DISPLAY INVISIBLE (-2900 1625);
FORCEPROP 2 LAST CDS_LOCATION Q8F1
J 0
(-2900 1575);
DISPLAY 0.617021 (-2900 1575);
PAINT AQUA (-2900 1575);
DISPLAY INVISIBLE (-2900 1575);
FORCEPROP 2 LAST SEC 1
J 0
(-2900 1675);
DISPLAY 0.680851 (-2900 1675);
PAINT MONO (-2900 1675);
DISPLAY INVISIBLE (-2900 1675);
FORCEPROP 2 LAST SEC_TYPE SOT23LF
J 0
(-2900 1675);
DISPLAY 1.021277 (-2900 1675);
PAINT ORANGE (-2900 1675);
DISPLAY INVISIBLE (-2900 1675);
FORCEPROP 0 LAST BOM_COST MIO_BIOS_MEM
J 0
(-2900 1775);
DISPLAY 1.021277 (-2900 1775);
PAINT ORANGE (-2900 1775);
DISPLAY INVISIBLE (-2900 1775);
FORCEPROP 2 LAST CDS_LIB mstr_discrete
J 0
(-3100 1575);
PAINT MONO (-3100 1575);
DISPLAY INVISIBLE (-3100 1575);
FORCEPROP 1 LAST PACK_TYPE SOT23LF
J 0
(-2900 1425);
DISPLAY 0.978723 (-2900 1425);
PAINT SKYBLUE (-2900 1425);
DISPLAY INVISIBLE (-2900 1425);
FORCEADD RES..2
R 2
(-3400 1750);
FORCEPROP 1 LAST PACK_TYPE 0402
J 2
(-3440 1575);
DISPLAY 0.617021 (-3440 1575);
PAINT SKYBLUE (-3440 1575);
FORCEPROP 1 LAST VALUE 4.75K
J 2
(-3445 1825);
DISPLAY 0.617021 (-3445 1825);
PAINT SKYBLUE (-3445 1825);
FORCEPROP 1 LAST LOCATION R2T6
J 2
(-3445 1875);
DISPLAY 0.617021 (-3445 1875);
PAINT AQUA (-3445 1875);
FORCEPROP 1 LAST TOLERANCE 1%
J 2
(-3445 1775);
DISPLAY 0.617021 (-3445 1775);
PAINT SKYBLUE (-3445 1775);
FORCEPROP 1 LASTPIN (-3400 1650) $PN 2
J 2
(-3405 1660);
DISPLAY 0.787234 (-3405 1660);
PAINT ORANGE (-3405 1660);
FORCEPROP 1 LASTPIN (-3400 1850) $PN 1
J 2
(-3405 1812);
DISPLAY 0.787234 (-3405 1812);
PAINT ORANGE (-3405 1812);
FORCEPROP 1 LAST WATTAGE 1/16W
J 2
(-3440 1725);
DISPLAY 0.617021 (-3440 1725);
PAINT SKYBLUE (-3440 1725);
FORCEPROP 1 LAST MATERIAL CHIP
J 2
(-3440 1675);
DISPLAY 0.617021 (-3440 1675);
PAINT SKYBLUE (-3440 1675);
FORCEPROP 1 LAST PART_NUMBER G21796-072
J 2
(-3440 1625);
DISPLAY 0.617021 (-3440 1625);
PAINT BLUE (-3440 1625);
FORCEPROP 2 LAST ROOM SB_BMC_SPI_MUX
J 2
(-3450 1925);
DISPLAY 1.021277 (-3450 1925);
PAINT ORANGE (-3450 1925);
DISPLAY INVISIBLE (-3450 1925);
FORCEPROP 1 LAST PATH I127
J 2
(-3450 1925);
DISPLAY 0.978723 (-3450 1925);
PAINT WHITE (-3450 1925);
DISPLAY INVISIBLE (-3450 1925);
FORCEPROP 2 LAST CDS_LOCATION R2T6
J 2
(-3445 1875);
DISPLAY 0.617021 (-3445 1875);
PAINT AQUA (-3445 1875);
DISPLAY INVISIBLE (-3445 1875);
FORCEPROP 2 LAST BOM_COST MIO_BIOS_MEM
J 2
(-3450 1975);
DISPLAY 1.021277 (-3450 1975);
PAINT ORANGE (-3450 1975);
DISPLAY INVISIBLE (-3450 1975);
FORCEPROP 2 LAST CDS_LIB mstr_discrete
J 0
(-3400 1750);
PAINT ORANGE (-3400 1750);
DISPLAY INVISIBLE (-3400 1750);
FORCEPROP 2 LAST SEC 1
J 0
(-3450 1975);
PAINT MONO (-3450 1975);
DISPLAY INVISIBLE (-3450 1975);
FORCEPROP 2 LAST SEC_TYPE 0402
J 0
(-3450 1975);
DISPLAY 1.021277 (-3450 1975);
PAINT ORANGE (-3450 1975);
DISPLAY INVISIBLE (-3450 1975);
FORCEADD RES..2
(-6250 2750);
FORCEPROP 1 LASTPIN (-6250 2850) $PN 1
J 0
(-6245 2812);
DISPLAY 0.617021 (-6245 2812);
PAINT ORANGE (-6245 2812);
FORCEPROP 1 LASTPIN (-6250 2650) $PN 2
J 0
(-6245 2660);
DISPLAY 0.617021 (-6245 2660);
PAINT ORANGE (-6245 2660);
FORCEPROP 1 LAST PACK_TYPE 0402
J 0
(-6210 2575);
DISPLAY 0.617021 (-6210 2575);
PAINT SKYBLUE (-6210 2575);
FORCEPROP 1 LAST TOLERANCE 1%
J 0
(-6205 2775);
DISPLAY 0.617021 (-6205 2775);
PAINT SKYBLUE (-6205 2775);
FORCEPROP 1 LAST VALUE 10.0K
J 0
(-6205 2825);
DISPLAY 0.617021 (-6205 2825);
PAINT SKYBLUE (-6205 2825);
FORCEPROP 1 LAST LOCATION R1U6
J 0
(-6205 2875);
DISPLAY 0.617021 (-6205 2875);
PAINT AQUA (-6205 2875);
FORCEPROP 1 LAST WATTAGE 1/16W
J 0
(-6210 2725);
DISPLAY 0.617021 (-6210 2725);
PAINT SKYBLUE (-6210 2725);
FORCEPROP 1 LAST MATERIAL CHIP
J 0
(-6210 2675);
DISPLAY 0.617021 (-6210 2675);
PAINT SKYBLUE (-6210 2675);
FORCEPROP 1 LAST PART_NUMBER G21796-016
J 0
(-6210 2625);
DISPLAY 0.617021 (-6210 2625);
PAINT BLUE (-6210 2625);
FORCEPROP 0 LAST ROOM SB_BMC_BPI_MUX
J 0
(-6200 2975);
DISPLAY 1.021277 (-6200 2975);
PAINT ORANGE (-6200 2975);
DISPLAY INVISIBLE (-6200 2975);
FORCEPROP 1 LAST PATH I128
J 0
(-6200 2925);
DISPLAY 0.978723 (-6200 2925);
PAINT WHITE (-6200 2925);
DISPLAY INVISIBLE (-6200 2925);
FORCEPROP 2 LAST CDS_LOCATION R1U6
J 0
(-6205 2875);
DISPLAY 0.617021 (-6205 2875);
PAINT AQUA (-6205 2875);
DISPLAY INVISIBLE (-6205 2875);
FORCEPROP 2 LAST SEC 1
J 0
(-6200 2975);
DISPLAY 0.680851 (-6200 2975);
PAINT MONO (-6200 2975);
DISPLAY INVISIBLE (-6200 2975);
FORCEPROP 2 LAST SEC_TYPE 0402
J 0
(-6200 2975);
DISPLAY 1.021277 (-6200 2975);
PAINT ORANGE (-6200 2975);
DISPLAY INVISIBLE (-6200 2975);
FORCEPROP 0 LAST BOM_COST MIO_BIOS_MEM
J 0
(-6200 3075);
DISPLAY 1.021277 (-6200 3075);
PAINT ORANGE (-6200 3075);
DISPLAY INVISIBLE (-6200 3075);
FORCEPROP 2 LAST CDS_LIB mstr_discrete
J 0
(-6250 2750);
PAINT MONO (-6250 2750);
DISPLAY INVISIBLE (-6250 2750);
FORCEADD GND..1
(-6250 2450);
FORCEPROP 3 LASTPIN (-6250 2500) SIG_NAME GND\g
J 0
(-6240 2510);
DISPLAY 0.659574 (-6240 2510);
PAINT MONO (-6240 2510);
DISPLAY INVISIBLE (-6240 2510);
FORCEPROP 1 LAST HDL_POWER GND
J 0
(-6250 2600);
DISPLAY 0.872340 (-6250 2600);
PAINT GREEN (-6250 2600);
DISPLAY INVISIBLE (-6250 2600);
FORCEPROP 1 LAST BODY_TYPE PLUMBING
J 0
(-6295 2407);
DISPLAY 0.340426 (-6295 2407);
PAINT GREEN (-6295 2407);
DISPLAY INVISIBLE (-6295 2407);
FORCEPROP 1 LAST PATH I129
J 0
(-6175 2450);
DISPLAY 0.872340 (-6175 2450);
PAINT AQUA (-6175 2450);
DISPLAY INVISIBLE (-6175 2450);
FORCEPROP 2 LAST CDS_LIB mstr_symbols
J 0
(-6250 2450);
PAINT MONO (-6250 2450);
DISPLAY INVISIBLE (-6250 2450);
FORCEPROP 1 LAST SIZE 1B
J 0
(-6175 2400);
DISPLAY 0.872340 (-6175 2400);
PAINT AQUA (-6175 2400);
DISPLAY INVISIBLE (-6175 2400);
FORCEPROP 1 LAST VOLTAGE 0.0V
J 0
(-6295 2407);
DISPLAY 0.340426 (-6295 2407);
PAINT SKYBLUE (-6295 2407);
DISPLAY INVISIBLE (-6295 2407);
FORCEADD GND..1
(-5400 4100);
FORCEPROP 3 LASTPIN (-5400 4150) SIG_NAME GND\g
J 0
(-5390 4160);
DISPLAY 0.659574 (-5390 4160);
PAINT MONO (-5390 4160);
DISPLAY INVISIBLE (-5390 4160);
FORCEPROP 1 LAST HDL_POWER GND
J 0
(-5400 4250);
DISPLAY 0.872340 (-5400 4250);
PAINT GREEN (-5400 4250);
DISPLAY INVISIBLE (-5400 4250);
FORCEPROP 1 LAST BODY_TYPE PLUMBING
J 0
(-5445 4057);
DISPLAY 0.340426 (-5445 4057);
PAINT GREEN (-5445 4057);
DISPLAY INVISIBLE (-5445 4057);
FORCEPROP 1 LAST PATH I13
J 0
(-5325 4100);
DISPLAY 0.872340 (-5325 4100);
PAINT AQUA (-5325 4100);
DISPLAY INVISIBLE (-5325 4100);
FORCEPROP 2 LAST CDS_LIB mstr_symbols
J 0
(-5400 4100);
PAINT ORANGE (-5400 4100);
DISPLAY INVISIBLE (-5400 4100);
FORCEPROP 1 LAST SIZE 1B
J 0
(-5325 4050);
DISPLAY 0.872340 (-5325 4050);
PAINT AQUA (-5325 4050);
DISPLAY INVISIBLE (-5325 4050);
FORCEPROP 1 LAST VOLTAGE 0.0V
J 0
(-5445 4057);
DISPLAY 0.340426 (-5445 4057);
PAINT SKYBLUE (-5445 4057);
DISPLAY INVISIBLE (-5445 4057);
FORCEADD OFFPAGE..2
(-5375 3000);
FORCEPROP 2 LAST $XR1 154 
J 0
(-5066 3000);
DISPLAY 0.638298 (-5066 3000);
PAINT MONO (-5066 3000);
FORCEPROP 2 LAST $XR0 147 
J 0
(-5186 3000);
DISPLAY 0.638298 (-5186 3000);
PAINT MONO (-5186 3000);
FORCEPROP 1 LAST COMMENT_BODY TRUE
J 0
(-5420 2905);
DISPLAY 0.872340 (-5420 2905);
PAINT GREEN (-5420 2905);
DISPLAY INVISIBLE (-5420 2905);
FORCEPROP 1 LAST OFFPAGE TRUE
J 0
(-5050 2875);
DISPLAY 0.872340 (-5050 2875);
PAINT GREEN (-5050 2875);
DISPLAY INVISIBLE (-5050 2875);
FORCEPROP 2 LAST PATH I130
J 0
(-5325 3075);
DISPLAY 1.021277 (-5325 3075);
PAINT ORANGE (-5325 3075);
DISPLAY INVISIBLE (-5325 3075);
FORCEPROP 2 LAST CDS_LIB mstr_standard
J 0
(-5375 3000);
PAINT MONO (-5375 3000);
DISPLAY INVISIBLE (-5375 3000);
FORCEADD P3V3_STBY..1
(-375 2525);
FORCEPROP 3 LASTPIN (-375 2475) SIG_NAME P3V3_STBY\g
J 0
(-365 2485);
DISPLAY 0.659574 (-365 2485);
PAINT MONO (-365 2485);
DISPLAY INVISIBLE (-365 2485);
FORCEPROP 1 LAST HDL_POWER P3V3_STBY
J 0
(-675 2400);
DISPLAY 0.872340 (-675 2400);
PAINT ORANGE (-675 2400);
DISPLAY INVISIBLE (-675 2400);
FORCEPROP 1 LAST BODY_TYPE PLUMBING
J 0
(-420 2482);
DISPLAY 0.340426 (-420 2482);
PAINT GREEN (-420 2482);
DISPLAY INVISIBLE (-420 2482);
FORCEPROP 1 LAST PATH I131
J 0
(-330 2527);
DISPLAY 0.340426 (-330 2527);
PAINT GREEN (-330 2527);
DISPLAY INVISIBLE (-330 2527);
FORCEPROP 1 LAST SIZE 1B
J 0
(-330 2547);
DISPLAY 0.340426 (-330 2547);
PAINT GREEN (-330 2547);
DISPLAY INVISIBLE (-330 2547);
FORCEPROP 2 LAST CDS_LIB mstr_symbols
J 0
(-375 2525);
PAINT ORANGE (-375 2525);
DISPLAY INVISIBLE (-375 2525);
FORCEPROP 1 LAST VOLTAGE 3.3V
J 0
(-420 2482);
DISPLAY 0.340426 (-420 2482);
PAINT SKYBLUE (-420 2482);
DISPLAY INVISIBLE (-420 2482);
FORCEADD CAP_A..1
(-375 2225);
FORCEPROP 1 LASTPIN (-375 2325) $PN 1
J 0
(-365 2305);
DISPLAY 0.617021 (-365 2305);
PAINT ORANGE (-365 2305);
FORCEPROP 1 LAST VOLTAGE 16V
J 0
(-325 2225);
DISPLAY 0.617021 (-325 2225);
PAINT SKYBLUE (-325 2225);
FORCEPROP 1 LAST TOLERANCE 10%
J 0
(-325 2175);
DISPLAY 0.617021 (-325 2175);
PAINT SKYBLUE (-325 2175);
FORCEPROP 1 LASTPIN (-375 2125) $PN 2
J 0
(-365 2105);
DISPLAY 0.617021 (-365 2105);
PAINT ORANGE (-365 2105);
FORCEPROP 1 LAST MATERIAL X7R
J 0
(-325 2125);
DISPLAY 0.617021 (-325 2125);
PAINT SKYBLUE (-325 2125);
FORCEPROP 1 LAST PART_NUMBER A36096-030
J 0
(-325 2075);
DISPLAY 0.617021 (-325 2075);
PAINT BLUE (-325 2075);
FORCEPROP 1 LAST PACK_TYPE 0402V
J 0
(-325 2025);
DISPLAY 0.617021 (-325 2025);
PAINT SKYBLUE (-325 2025);
FORCEPROP 1 LAST VALUE 0.1UF
J 0
(-325 2275);
DISPLAY 0.617021 (-325 2275);
PAINT SKYBLUE (-325 2275);
FORCEPROP 1 LAST LOCATION C2T12
J 0
(-325 2325);
DISPLAY 0.617021 (-325 2325);
PAINT AQUA (-325 2325);
FORCEPROP 2 LAST SEC 1
J 0
(-325 2375);
DISPLAY 0.680851 (-325 2375);
PAINT MONO (-325 2375);
DISPLAY INVISIBLE (-325 2375);
FORCEPROP 2 LAST SEC_TYPE 0402V
J 0
(-325 2425);
DISPLAY 1.021277 (-325 2425);
PAINT ORANGE (-325 2425);
DISPLAY INVISIBLE (-325 2425);
FORCEPROP 2 LAST CDS_SEC 1
J 0
(-325 2375);
PAINT ORANGE (-325 2375);
DISPLAY INVISIBLE (-325 2375);
FORCEPROP 2 LAST CDS_LIB dev_discrete
J 0
(-375 2225);
PAINT ORANGE (-375 2225);
DISPLAY INVISIBLE (-375 2225);
FORCEPROP 2 LAST BOM_COST MIO_BIOS_MEM
J 0
(-325 2425);
DISPLAY 1.021277 (-325 2425);
PAINT ORANGE (-325 2425);
DISPLAY INVISIBLE (-325 2425);
FORCEPROP 2 LAST CDS_LOCATION C2T12
J 0
(-325 2325);
DISPLAY 0.617021 (-325 2325);
PAINT AQUA (-325 2325);
DISPLAY INVISIBLE (-325 2325);
FORCEPROP 2 LAST ROOM SB_BMC_SPI_MUX
J 0
(-325 2375);
DISPLAY 1.021277 (-325 2375);
PAINT ORANGE (-325 2375);
DISPLAY INVISIBLE (-325 2375);
FORCEPROP 1 LAST PATH I132
J 0
(-325 2375);
DISPLAY 0.978723 (-325 2375);
PAINT WHITE (-325 2375);
DISPLAY INVISIBLE (-325 2375);
FORCEADD GND..1
(-375 1925);
FORCEPROP 3 LASTPIN (-375 1975) SIG_NAME GND\g
J 0
(-365 1985);
DISPLAY 0.659574 (-365 1985);
PAINT MONO (-365 1985);
DISPLAY INVISIBLE (-365 1985);
FORCEPROP 1 LAST HDL_POWER GND
J 0
(-375 2075);
DISPLAY 0.872340 (-375 2075);
PAINT GREEN (-375 2075);
DISPLAY INVISIBLE (-375 2075);
FORCEPROP 1 LAST BODY_TYPE PLUMBING
J 0
(-420 1882);
DISPLAY 0.340426 (-420 1882);
PAINT GREEN (-420 1882);
DISPLAY INVISIBLE (-420 1882);
FORCEPROP 1 LAST PATH I133
J 0
(-300 1925);
DISPLAY 0.872340 (-300 1925);
PAINT AQUA (-300 1925);
DISPLAY INVISIBLE (-300 1925);
FORCEPROP 1 LAST SIZE 1B
J 0
(-300 1875);
DISPLAY 0.872340 (-300 1875);
PAINT AQUA (-300 1875);
DISPLAY INVISIBLE (-300 1875);
FORCEPROP 2 LAST CDS_LIB mstr_symbols
J 0
(-375 1925);
PAINT ORANGE (-375 1925);
DISPLAY INVISIBLE (-375 1925);
FORCEPROP 1 LAST VOLTAGE 0.0V
J 0
(-420 1882);
DISPLAY 0.340426 (-420 1882);
PAINT SKYBLUE (-420 1882);
DISPLAY INVISIBLE (-420 1882);
FORCEADD P3V3_STBY..1
(-375 1700);
FORCEPROP 3 LASTPIN (-375 1650) SIG_NAME P3V3_STBY\g
J 0
(-365 1660);
DISPLAY 0.659574 (-365 1660);
PAINT MONO (-365 1660);
DISPLAY INVISIBLE (-365 1660);
FORCEPROP 1 LAST HDL_POWER P3V3_STBY
J 0
(-675 1575);
DISPLAY 0.872340 (-675 1575);
PAINT ORANGE (-675 1575);
DISPLAY INVISIBLE (-675 1575);
FORCEPROP 1 LAST BODY_TYPE PLUMBING
J 0
(-420 1657);
DISPLAY 0.340426 (-420 1657);
PAINT GREEN (-420 1657);
DISPLAY INVISIBLE (-420 1657);
FORCEPROP 1 LAST PATH I134
J 0
(-330 1702);
DISPLAY 0.340426 (-330 1702);
PAINT GREEN (-330 1702);
DISPLAY INVISIBLE (-330 1702);
FORCEPROP 1 LAST SIZE 1B
J 0
(-330 1722);
DISPLAY 0.340426 (-330 1722);
PAINT GREEN (-330 1722);
DISPLAY INVISIBLE (-330 1722);
FORCEPROP 2 LAST CDS_LIB mstr_symbols
J 0
(-375 1700);
PAINT ORANGE (-375 1700);
DISPLAY INVISIBLE (-375 1700);
FORCEPROP 1 LAST VOLTAGE 3.3V
J 0
(-420 1657);
DISPLAY 0.340426 (-420 1657);
PAINT SKYBLUE (-420 1657);
DISPLAY INVISIBLE (-420 1657);
FORCEADD CAP_A..1
(-375 1475);
FORCEPROP 1 LAST TOLERANCE 10%
J 0
(-325 1425);
DISPLAY 0.617021 (-325 1425);
PAINT SKYBLUE (-325 1425);
FORCEPROP 1 LAST VOLTAGE 16V
J 0
(-325 1475);
DISPLAY 0.617021 (-325 1475);
PAINT SKYBLUE (-325 1475);
FORCEPROP 1 LAST MATERIAL X7R
J 0
(-325 1375);
DISPLAY 0.617021 (-325 1375);
PAINT SKYBLUE (-325 1375);
FORCEPROP 1 LASTPIN (-375 1575) $PN 1
J 0
(-365 1555);
DISPLAY 0.617021 (-365 1555);
PAINT ORANGE (-365 1555);
FORCEPROP 1 LASTPIN (-375 1375) $PN 2
J 0
(-365 1355);
DISPLAY 0.617021 (-365 1355);
PAINT ORANGE (-365 1355);
FORCEPROP 1 LAST VALUE 0.1UF
J 0
(-325 1525);
DISPLAY 0.617021 (-325 1525);
PAINT SKYBLUE (-325 1525);
FORCEPROP 1 LAST LOCATION C2T8
J 0
(-325 1575);
DISPLAY 0.617021 (-325 1575);
PAINT AQUA (-325 1575);
FORCEPROP 1 LAST PART_NUMBER A36096-030
J 0
(-325 1325);
DISPLAY 0.617021 (-325 1325);
PAINT BLUE (-325 1325);
FORCEPROP 1 LAST PACK_TYPE 0402V
J 0
(-325 1275);
DISPLAY 0.617021 (-325 1275);
PAINT SKYBLUE (-325 1275);
FORCEPROP 1 LAST PATH I135
J 0
(-325 1625);
DISPLAY 0.978723 (-325 1625);
PAINT WHITE (-325 1625);
DISPLAY INVISIBLE (-325 1625);
FORCEPROP 2 LAST ROOM SB_BMC_SPI_MUX
J 0
(-325 1625);
DISPLAY 1.021277 (-325 1625);
PAINT ORANGE (-325 1625);
DISPLAY INVISIBLE (-325 1625);
FORCEPROP 2 LAST CDS_LOCATION C2T8
J 0
(-325 1575);
DISPLAY 0.617021 (-325 1575);
PAINT AQUA (-325 1575);
DISPLAY INVISIBLE (-325 1575);
FORCEPROP 2 LAST BOM_COST MIO_BIOS_MEM
J 0
(-325 1675);
DISPLAY 1.021277 (-325 1675);
PAINT ORANGE (-325 1675);
DISPLAY INVISIBLE (-325 1675);
FORCEPROP 2 LAST CDS_LIB dev_discrete
J 0
(-375 1475);
PAINT ORANGE (-375 1475);
DISPLAY INVISIBLE (-375 1475);
FORCEPROP 2 LAST CDS_SEC 1
J 0
(-325 1625);
PAINT ORANGE (-325 1625);
DISPLAY INVISIBLE (-325 1625);
FORCEPROP 2 LAST SEC_TYPE 0402V
J 0
(-325 1675);
DISPLAY 1.021277 (-325 1675);
PAINT ORANGE (-325 1675);
DISPLAY INVISIBLE (-325 1675);
FORCEPROP 2 LAST SEC 1
J 0
(-325 1625);
DISPLAY 0.680851 (-325 1625);
PAINT MONO (-325 1625);
DISPLAY INVISIBLE (-325 1625);
FORCEADD GND..1
(-375 1250);
FORCEPROP 3 LASTPIN (-375 1300) SIG_NAME GND\g
J 0
(-365 1310);
DISPLAY 0.659574 (-365 1310);
PAINT MONO (-365 1310);
DISPLAY INVISIBLE (-365 1310);
FORCEPROP 1 LAST HDL_POWER GND
J 0
(-375 1400);
DISPLAY 0.872340 (-375 1400);
PAINT GREEN (-375 1400);
DISPLAY INVISIBLE (-375 1400);
FORCEPROP 1 LAST BODY_TYPE PLUMBING
J 0
(-420 1207);
DISPLAY 0.340426 (-420 1207);
PAINT GREEN (-420 1207);
DISPLAY INVISIBLE (-420 1207);
FORCEPROP 1 LAST VOLTAGE 0.0V
J 0
(-420 1207);
DISPLAY 0.340426 (-420 1207);
PAINT SKYBLUE (-420 1207);
DISPLAY INVISIBLE (-420 1207);
FORCEPROP 2 LAST CDS_LIB mstr_symbols
J 0
(-375 1250);
PAINT ORANGE (-375 1250);
DISPLAY INVISIBLE (-375 1250);
FORCEPROP 1 LAST SIZE 1B
J 0
(-300 1200);
DISPLAY 0.872340 (-300 1200);
PAINT AQUA (-300 1200);
DISPLAY INVISIBLE (-300 1200);
FORCEPROP 1 LAST PATH I136
J 0
(-300 1250);
DISPLAY 0.872340 (-300 1250);
PAINT AQUA (-300 1250);
DISPLAY INVISIBLE (-300 1250);
FORCEADD P3V3_STBY..1
(-3400 2025);
FORCEPROP 3 LASTPIN (-3400 1975) SIG_NAME P3V3_STBY\g
J 0
(-3390 1985);
DISPLAY 0.659574 (-3390 1985);
PAINT MONO (-3390 1985);
DISPLAY INVISIBLE (-3390 1985);
FORCEPROP 1 LAST HDL_POWER P3V3_STBY
J 0
(-3700 1900);
DISPLAY 0.872340 (-3700 1900);
PAINT ORANGE (-3700 1900);
DISPLAY INVISIBLE (-3700 1900);
FORCEPROP 1 LAST BODY_TYPE PLUMBING
J 0
(-3445 1982);
DISPLAY 0.340426 (-3445 1982);
PAINT GREEN (-3445 1982);
DISPLAY INVISIBLE (-3445 1982);
FORCEPROP 1 LAST PATH I137
J 0
(-3355 2027);
DISPLAY 0.340426 (-3355 2027);
PAINT GREEN (-3355 2027);
DISPLAY INVISIBLE (-3355 2027);
FORCEPROP 2 LAST CDS_LIB mstr_symbols
J 0
(-3400 2025);
PAINT ORANGE (-3400 2025);
DISPLAY INVISIBLE (-3400 2025);
FORCEPROP 1 LAST SIZE 1B
J 0
(-3355 2047);
DISPLAY 0.340426 (-3355 2047);
PAINT GREEN (-3355 2047);
DISPLAY INVISIBLE (-3355 2047);
FORCEPROP 1 LAST VOLTAGE 3.3V
J 0
(-3445 1982);
DISPLAY 0.340426 (-3445 1982);
PAINT SKYBLUE (-3445 1982);
DISPLAY INVISIBLE (-3445 1982);
FORCEADD OFFPAGE..1
(-4500 1100);
FORCEPROP 2 LAST $XR1 153 
J 0
(-4872 1100);
DISPLAY 0.638298 (-4872 1100);
PAINT MONO (-4872 1100);
FORCEPROP 2 LAST $XR0 154 
J 0
(-4752 1100);
DISPLAY 0.638298 (-4752 1100);
PAINT MONO (-4752 1100);
FORCEPROP 1 LAST COMMENT_BODY TRUE
J 0
(-4375 1000);
DISPLAY 0.872340 (-4375 1000);
PAINT GREEN (-4375 1000);
DISPLAY INVISIBLE (-4375 1000);
FORCEPROP 1 LAST OFFPAGE TRUE
J 0
(-4175 975);
DISPLAY 0.872340 (-4175 975);
PAINT GREEN (-4175 975);
DISPLAY INVISIBLE (-4175 975);
FORCEPROP 2 LAST CDS_LIB mstr_standard
J 0
(-4500 1100);
PAINT ORANGE (-4500 1100);
DISPLAY INVISIBLE (-4500 1100);
FORCEPROP 2 LAST PATH I138
J 0
(-4450 1175);
DISPLAY 1.021277 (-4450 1175);
PAINT ORANGE (-4450 1175);
DISPLAY INVISIBLE (-4450 1175);
FORCEADD CAP_A..1
(-5400 4350);
FORCEPROP 1 LAST PACK_TYPE 0402V
J 0
(-5350 4150);
DISPLAY 0.617021 (-5350 4150);
PAINT SKYBLUE (-5350 4150);
FORCEPROP 1 LASTPIN (-5400 4250) $PN 2
J 0
(-5390 4230);
DISPLAY 0.617021 (-5390 4230);
PAINT ORANGE (-5390 4230);
FORCEPROP 1 LASTPIN (-5400 4450) $PN 1
J 0
(-5390 4430);
DISPLAY 0.617021 (-5390 4430);
PAINT ORANGE (-5390 4430);
FORCEPROP 1 LAST MATERIAL X7R
J 0
(-5350 4250);
DISPLAY 0.617021 (-5350 4250);
PAINT SKYBLUE (-5350 4250);
FORCEPROP 1 LAST VOLTAGE 16V
J 0
(-5350 4350);
DISPLAY 0.617021 (-5350 4350);
PAINT SKYBLUE (-5350 4350);
FORCEPROP 1 LAST TOLERANCE 10%
J 0
(-5350 4300);
DISPLAY 0.617021 (-5350 4300);
PAINT SKYBLUE (-5350 4300);
FORCEPROP 1 LAST VALUE 0.1UF
J 0
(-5350 4400);
DISPLAY 0.617021 (-5350 4400);
PAINT SKYBLUE (-5350 4400);
FORCEPROP 1 LAST PART_NUMBER A36096-030
J 0
(-5350 4200);
DISPLAY 0.617021 (-5350 4200);
PAINT BLUE (-5350 4200);
FORCEPROP 1 LAST LOCATION C8E18
J 0
(-5350 4450);
DISPLAY 0.617021 (-5350 4450);
PAINT AQUA (-5350 4450);
FORCEPROP 2 LAST SEC 1
J 0
(-5350 4550);
DISPLAY 0.680851 (-5350 4550);
PAINT MONO (-5350 4550);
DISPLAY INVISIBLE (-5350 4550);
FORCEPROP 2 LAST SEC_TYPE 0402V
J 0
(-5350 4550);
DISPLAY 1.021277 (-5350 4550);
PAINT ORANGE (-5350 4550);
DISPLAY INVISIBLE (-5350 4550);
FORCEPROP 2 LAST CDS_SEC 1
J 0
(-5350 4500);
PAINT ORANGE (-5350 4500);
DISPLAY INVISIBLE (-5350 4500);
FORCEPROP 2 LAST CDS_LIB dev_discrete
J 0
(-5400 4350);
PAINT ORANGE (-5400 4350);
DISPLAY INVISIBLE (-5400 4350);
FORCEPROP 2 LAST BOM_COST MIO_BIOS_MEM
J 0
(-5350 4550);
DISPLAY 1.021277 (-5350 4550);
PAINT ORANGE (-5350 4550);
DISPLAY INVISIBLE (-5350 4550);
FORCEPROP 2 LAST CDS_LOCATION C8E18
J 0
(-5350 4450);
DISPLAY 0.617021 (-5350 4450);
PAINT AQUA (-5350 4450);
DISPLAY INVISIBLE (-5350 4450);
FORCEPROP 2 LAST ROOM SB_BMC_SPI_MUX
J 0
(-5350 4500);
DISPLAY 1.021277 (-5350 4500);
PAINT ORANGE (-5350 4500);
DISPLAY INVISIBLE (-5350 4500);
FORCEPROP 1 LAST PATH I14
J 0
(-5350 4500);
DISPLAY 0.978723 (-5350 4500);
PAINT WHITE (-5350 4500);
DISPLAY INVISIBLE (-5350 4500);
FORCEADD RES..1
(-1450 1150);
FORCEPROP 1 LAST PACK_TYPE 0402
J 0
(-1200 1100);
DISPLAY 0.617021 (-1200 1100);
PAINT SKYBLUE (-1200 1100);
FORCEPROP 1 LAST LOCATION R2T9
J 0
(-1450 1200);
DISPLAY 0.617021 (-1450 1200);
PAINT AQUA (-1450 1200);
FORCEPROP 1 LASTPIN (-1350 1150) $PN 2
J 0
(-1388 1162);
DISPLAY 0.617021 (-1388 1162);
PAINT ORANGE (-1388 1162);
FORCEPROP 1 LAST VALUE 75
J 2
(-1500 1100);
DISPLAY 0.617021 (-1500 1100);
PAINT SKYBLUE (-1500 1100);
FORCEPROP 1 LAST TOLERANCE 1.0%
J 0
(-1650 1100);
DISPLAY 0.617021 (-1650 1100);
PAINT SKYBLUE (-1650 1100);
FORCEPROP 1 LASTPIN (-1550 1150) $PN 1
J 0
(-1538 1162);
DISPLAY 0.617021 (-1538 1162);
PAINT ORANGE (-1538 1162);
FORCEPROP 1 LAST WATTAGE 1/16W
J 2
(-1325 1100);
DISPLAY 0.617021 (-1325 1100);
PAINT SKYBLUE (-1325 1100);
FORCEPROP 1 LAST PART_NUMBER G21796-267
J 0
(-1525 1050);
DISPLAY 0.617021 (-1525 1050);
PAINT BLUE (-1525 1050);
FORCEPROP 1 LAST MATERIAL CHIP
J 0
(-1300 1100);
DISPLAY 0.617021 (-1300 1100);
PAINT SKYBLUE (-1300 1100);
FORCEPROP 0 LAST GROUP NI_BIOS_ROM2
J 0
(-1532 999);
DISPLAY 0.638298 (-1532 999);
PAINT BROWN (-1532 999);
DISPLAY BOTH (-1532 999);
FORCEPROP 2 LAST ROOM SB_BMC_SPI_MUX
J 0
(-1450 1250);
DISPLAY 1.021277 (-1450 1250);
PAINT ORANGE (-1450 1250);
DISPLAY INVISIBLE (-1450 1250);
FORCEPROP 1 LAST PATH I62
J 0
(-1500 1300);
DISPLAY 0.978723 (-1500 1300);
PAINT WHITE (-1500 1300);
DISPLAY INVISIBLE (-1500 1300);
FORCEPROP 2 LAST CDS_LOCATION R2T9
J 0
(-1450 1200);
DISPLAY 0.617021 (-1450 1200);
PAINT AQUA (-1450 1200);
DISPLAY INVISIBLE (-1450 1200);
FORCEPROP 2 LAST SEC 1
J 0
(-1500 1350);
DISPLAY 0.680851 (-1500 1350);
PAINT MONO (-1500 1350);
DISPLAY INVISIBLE (-1500 1350);
FORCEPROP 2 LAST SEC_TYPE 0402
J 0
(-1500 1350);
DISPLAY 1.021277 (-1500 1350);
PAINT ORANGE (-1500 1350);
DISPLAY INVISIBLE (-1500 1350);
FORCEPROP 2 LAST CDS_LIB mstr_discrete
J 0
(-1450 1150);
PAINT ORANGE (-1450 1150);
DISPLAY INVISIBLE (-1450 1150);
FORCEPROP 2 LAST BOM_COST MIO_BIOS_MEM
J 0
(-1450 1300);
DISPLAY 1.021277 (-1450 1300);
PAINT ORANGE (-1450 1300);
DISPLAY INVISIBLE (-1450 1300);
FORCEADD OFFPAGE..5
R 2
(-4850 3900);
FORCEPROP 2 LAST $XR0 153 
J 0
(-4661 3900);
DISPLAY 0.638298 (-4661 3900);
PAINT MONO (-4661 3900);
FORCEPROP 1 LAST COMMENT_BODY TRUE
J 2
(-4950 3825);
DISPLAY 0.872340 (-4950 3825);
PAINT GREEN (-4950 3825);
DISPLAY INVISIBLE (-4950 3825);
FORCEPROP 1 LAST OFFPAGE TRUE
J 2
(-5175 3775);
DISPLAY 0.872340 (-5175 3775);
PAINT GREEN (-5175 3775);
DISPLAY INVISIBLE (-5175 3775);
FORCEPROP 2 LAST PATH I70
J 2
(-4600 3950);
DISPLAY 1.021277 (-4600 3950);
PAINT ORANGE (-4600 3950);
DISPLAY INVISIBLE (-4600 3950);
FORCEPROP 2 LAST CDS_LIB mstr_standard
J 2
(-4850 3900);
PAINT ORANGE (-4850 3900);
DISPLAY INVISIBLE (-4850 3900);
FORCEADD OFFPAGE..5
R 2
(-4850 3800);
FORCEPROP 2 LAST $XR0 153 
J 0
(-4661 3800);
DISPLAY 0.638298 (-4661 3800);
PAINT MONO (-4661 3800);
FORCEPROP 1 LAST COMMENT_BODY TRUE
J 2
(-4950 3725);
DISPLAY 0.872340 (-4950 3725);
PAINT GREEN (-4950 3725);
DISPLAY INVISIBLE (-4950 3725);
FORCEPROP 1 LAST OFFPAGE TRUE
J 2
(-5175 3675);
DISPLAY 0.872340 (-5175 3675);
PAINT GREEN (-5175 3675);
DISPLAY INVISIBLE (-5175 3675);
FORCEPROP 2 LAST PATH I71
J 2
(-4600 3850);
DISPLAY 1.021277 (-4600 3850);
PAINT ORANGE (-4600 3850);
DISPLAY INVISIBLE (-4600 3850);
FORCEPROP 2 LAST CDS_LIB mstr_standard
J 2
(-4850 3800);
PAINT ORANGE (-4850 3800);
DISPLAY INVISIBLE (-4850 3800);
FORCEADD OFFPAGE..5
R 2
(-4850 3700);
FORCEPROP 2 LAST $XR1 154 
J 0
(-4541 3700);
DISPLAY 0.638298 (-4541 3700);
PAINT MONO (-4541 3700);
FORCEPROP 2 LAST $XR0 153 
J 0
(-4661 3700);
DISPLAY 0.638298 (-4661 3700);
PAINT MONO (-4661 3700);
FORCEPROP 1 LAST COMMENT_BODY TRUE
J 2
(-4950 3625);
DISPLAY 0.872340 (-4950 3625);
PAINT GREEN (-4950 3625);
DISPLAY INVISIBLE (-4950 3625);
FORCEPROP 1 LAST OFFPAGE TRUE
J 2
(-5175 3575);
DISPLAY 0.872340 (-5175 3575);
PAINT GREEN (-5175 3575);
DISPLAY INVISIBLE (-5175 3575);
FORCEPROP 2 LAST PATH I72
J 2
(-4600 3750);
DISPLAY 1.021277 (-4600 3750);
PAINT ORANGE (-4600 3750);
DISPLAY INVISIBLE (-4600 3750);
FORCEPROP 2 LAST CDS_LIB mstr_standard
J 2
(-4850 3700);
PAINT ORANGE (-4850 3700);
DISPLAY INVISIBLE (-4850 3700);
FORCEADD OFFPAGE..1
R 2
(-4850 3600);
FORCEPROP 2 LAST $XR0 153 
J 0
(-4664 3600);
DISPLAY 0.638298 (-4664 3600);
PAINT MONO (-4664 3600);
FORCEPROP 1 LAST COMMENT_BODY TRUE
J 2
(-4975 3500);
DISPLAY 0.872340 (-4975 3500);
PAINT GREEN (-4975 3500);
DISPLAY INVISIBLE (-4975 3500);
FORCEPROP 1 LAST OFFPAGE TRUE
J 2
(-5175 3475);
DISPLAY 0.872340 (-5175 3475);
PAINT GREEN (-5175 3475);
DISPLAY INVISIBLE (-5175 3475);
FORCEPROP 2 LAST PATH I73
J 2
(-4600 3650);
DISPLAY 1.021277 (-4600 3650);
PAINT ORANGE (-4600 3650);
DISPLAY INVISIBLE (-4600 3650);
FORCEPROP 2 LAST CDS_LIB mstr_standard
J 2
(-4850 3600);
PAINT ORANGE (-4850 3600);
DISPLAY INVISIBLE (-4850 3600);
FORCEADD PI3B3257A..1
R 2
(-5900 3700);
FORCEPROP 2 LASTPIN (-5700 3500) $PN 8
J 0
(-5690 3510);
DISPLAY 0.617021 (-5690 3510);
PAINT ORANGE (-5690 3510);
FORCEPROP 2 LASTPIN (-6100 3900) $PN 2
J 2
(-6110 3910);
DISPLAY 0.617021 (-6110 3910);
PAINT ORANGE (-6110 3910);
FORCEPROP 2 LASTPIN (-6100 3850) $PN 3
J 2
(-6110 3860);
DISPLAY 0.617021 (-6110 3860);
PAINT ORANGE (-6110 3860);
FORCEPROP 2 LASTPIN (-6100 3800) $PN 5
J 2
(-6110 3810);
DISPLAY 0.617021 (-6110 3810);
PAINT ORANGE (-6110 3810);
FORCEPROP 2 LASTPIN (-6100 3750) $PN 6
J 2
(-6110 3760);
DISPLAY 0.617021 (-6110 3760);
PAINT ORANGE (-6110 3760);
FORCEPROP 2 LASTPIN (-6100 3700) $PN 11
J 2
(-6110 3710);
DISPLAY 0.617021 (-6110 3710);
PAINT ORANGE (-6110 3710);
FORCEPROP 2 LASTPIN (-6100 3650) $PN 10
J 2
(-6110 3660);
DISPLAY 0.617021 (-6110 3660);
PAINT ORANGE (-6110 3660);
FORCEPROP 2 LASTPIN (-6100 3600) $PN 14
J 2
(-6110 3610);
DISPLAY 0.617021 (-6110 3610);
PAINT ORANGE (-6110 3610);
FORCEPROP 2 LASTPIN (-6100 3950) $PN 1
J 2
(-6110 3960);
DISPLAY 0.617021 (-6110 3960);
PAINT ORANGE (-6110 3960);
FORCEPROP 2 LASTPIN (-5700 4000) $PN 16
J 0
(-5690 4010);
DISPLAY 0.617021 (-5690 4010);
PAINT ORANGE (-5690 4010);
FORCEPROP 2 LASTPIN (-5700 3900) $PN 4
J 0
(-5690 3910);
DISPLAY 0.617021 (-5690 3910);
PAINT ORANGE (-5690 3910);
FORCEPROP 2 LASTPIN (-5700 3800) $PN 7
J 0
(-5690 3810);
DISPLAY 0.617021 (-5690 3810);
PAINT ORANGE (-5690 3810);
FORCEPROP 2 LASTPIN (-5700 3700) $PN 9
J 0
(-5690 3710);
DISPLAY 0.617021 (-5690 3710);
PAINT ORANGE (-5690 3710);
FORCEPROP 2 LASTPIN (-5700 3600) $PN 12
J 0
(-5690 3610);
DISPLAY 0.617021 (-5690 3610);
PAINT ORANGE (-5690 3610);
FORCEPROP 1 LAST MATERIAL IC
J 2
(-5750 4100);
DISPLAY 0.617021 (-5750 4100);
PAINT SKYBLUE (-5750 4100);
FORCEPROP 1 LAST LOCATION U8F1
J 2
(-5850 4125);
DISPLAY 0.617021 (-5850 4125);
PAINT AQUA (-5850 4125);
FORCEPROP 2 LASTPIN (-6100 3550) $PN 13
J 2
(-6110 3560);
DISPLAY 0.617021 (-6110 3560);
PAINT ORANGE (-6110 3560);
FORCEPROP 1 LAST PART_NUMBER E16801-001
J 2
(-5750 3400);
DISPLAY 0.617021 (-5750 3400);
PAINT BLUE (-5750 3400);
FORCEPROP 2 LASTPIN (-6100 4000) $PN 15
J 2
(-6110 4010);
DISPLAY 0.617021 (-6110 4010);
PAINT ORANGE (-6110 4010);
FORCEPROP 2 LAST ROOM SB_BMC_SPI_MUX
J 0
(-5750 4175);
DISPLAY 1.021277 (-5750 4175);
PAINT ORANGE (-5750 4175);
DISPLAY INVISIBLE (-5750 4175);
FORCEPROP 1 LAST PATH I74
J 2
(-6025 4075);
DISPLAY 0.468085 (-6025 4075);
PAINT GREEN (-6025 4075);
DISPLAY INVISIBLE (-6025 4075);
FORCEPROP 2 LAST CDS_LOCATION U8F1
J 2
(-5750 4125);
DISPLAY 0.617021 (-5750 4125);
PAINT AQUA (-5750 4125);
DISPLAY INVISIBLE (-5750 4125);
FORCEPROP 2 LAST SEC 1
J 2
(-5750 4150);
DISPLAY 0.680851 (-5750 4150);
PAINT MONO (-5750 4150);
DISPLAY INVISIBLE (-5750 4150);
FORCEPROP 2 LAST CDS_LIB mstr_digital
J 2
(-5900 3700);
PAINT ORANGE (-5900 3700);
DISPLAY INVISIBLE (-5900 3700);
FORCEPROP 2 LAST SEC_TYPE TSSOPLF
J 2
(-5750 4150);
DISPLAY 1.021277 (-5750 4150);
PAINT ORANGE (-5750 4150);
DISPLAY INVISIBLE (-5750 4150);
FORCEPROP 2 LAST BOM_COST MIO_BIOS_MEM
J 0
(-5750 4225);
DISPLAY 1.021277 (-5750 4225);
PAINT ORANGE (-5750 4225);
DISPLAY INVISIBLE (-5750 4225);
FORCEPROP 1 LAST PACK_TYPE TSSOPLF
J 2
(-5750 4150);
DISPLAY 0.468085 (-5750 4150);
PAINT SKYBLUE (-5750 4150);
DISPLAY INVISIBLE (-5750 4150);
FORCEADD PI3B3257A..1
R 2
(-2000 3875);
FORCEPROP 2 LASTPIN (-2200 4175) $PN 15
J 2
(-2210 4185);
DISPLAY 0.617021 (-2210 4185);
PAINT ORANGE (-2210 4185);
FORCEPROP 2 LASTPIN (-1800 3675) $PN 8
J 0
(-1790 3685);
DISPLAY 0.617021 (-1790 3685);
PAINT ORANGE (-1790 3685);
FORCEPROP 2 LASTPIN (-2200 4025) $PN 3
J 2
(-2210 4035);
DISPLAY 0.617021 (-2210 4035);
PAINT ORANGE (-2210 4035);
FORCEPROP 2 LASTPIN (-2200 3975) $PN 5
J 2
(-2210 3985);
DISPLAY 0.617021 (-2210 3985);
PAINT ORANGE (-2210 3985);
FORCEPROP 2 LASTPIN (-2200 3925) $PN 6
J 2
(-2210 3935);
DISPLAY 0.617021 (-2210 3935);
PAINT ORANGE (-2210 3935);
FORCEPROP 2 LASTPIN (-2200 3875) $PN 11
J 2
(-2210 3885);
DISPLAY 0.617021 (-2210 3885);
PAINT ORANGE (-2210 3885);
FORCEPROP 2 LASTPIN (-2200 3825) $PN 10
J 2
(-2210 3835);
DISPLAY 0.617021 (-2210 3835);
PAINT ORANGE (-2210 3835);
FORCEPROP 2 LASTPIN (-2200 3775) $PN 14
J 2
(-2210 3785);
DISPLAY 0.617021 (-2210 3785);
PAINT ORANGE (-2210 3785);
FORCEPROP 2 LASTPIN (-2200 3725) $PN 13
J 2
(-2210 3735);
DISPLAY 0.617021 (-2210 3735);
PAINT ORANGE (-2210 3735);
FORCEPROP 2 LASTPIN (-2200 4125) $PN 1
J 2
(-2210 4135);
DISPLAY 0.617021 (-2210 4135);
PAINT ORANGE (-2210 4135);
FORCEPROP 2 LASTPIN (-1800 4175) $PN 16
J 0
(-1790 4185);
DISPLAY 0.617021 (-1790 4185);
PAINT ORANGE (-1790 4185);
FORCEPROP 2 LASTPIN (-1800 3975) $PN 7
J 0
(-1790 3985);
DISPLAY 0.617021 (-1790 3985);
PAINT ORANGE (-1790 3985);
FORCEPROP 2 LASTPIN (-1800 3875) $PN 9
J 0
(-1790 3885);
DISPLAY 0.617021 (-1790 3885);
PAINT ORANGE (-1790 3885);
FORCEPROP 2 LASTPIN (-1800 3775) $PN 12
J 0
(-1790 3785);
DISPLAY 0.617021 (-1790 3785);
PAINT ORANGE (-1790 3785);
FORCEPROP 1 LAST MATERIAL IC
J 2
(-1850 4275);
DISPLAY 0.617021 (-1850 4275);
PAINT SKYBLUE (-1850 4275);
FORCEPROP 1 LAST PART_NUMBER E16801-001
J 2
(-1875 3575);
DISPLAY 0.617021 (-1875 3575);
PAINT BLUE (-1875 3575);
FORCEPROP 1 LAST LOCATION U2T1
J 2
(-1975 4300);
DISPLAY 0.617021 (-1975 4300);
PAINT AQUA (-1975 4300);
FORCEPROP 2 LASTPIN (-2200 4075) $PN 2
J 2
(-2210 4085);
DISPLAY 0.617021 (-2210 4085);
PAINT ORANGE (-2210 4085);
FORCEPROP 2 LASTPIN (-1800 4075) $PN 4
J 0
(-1790 4085);
DISPLAY 0.617021 (-1790 4085);
PAINT ORANGE (-1790 4085);
FORCEPROP 2 LAST ROOM SB_BMC_SPI_MUX
J 0
(-1850 4350);
DISPLAY 1.021277 (-1850 4350);
PAINT ORANGE (-1850 4350);
DISPLAY INVISIBLE (-1850 4350);
FORCEPROP 1 LAST PATH I75
J 2
(-2125 4250);
DISPLAY 0.468085 (-2125 4250);
PAINT GREEN (-2125 4250);
DISPLAY INVISIBLE (-2125 4250);
FORCEPROP 2 LAST CDS_LOCATION U2T1
J 2
(-1850 4300);
DISPLAY 0.617021 (-1850 4300);
PAINT AQUA (-1850 4300);
DISPLAY INVISIBLE (-1850 4300);
FORCEPROP 2 LAST SEC 1
J 2
(-1850 4325);
DISPLAY 0.680851 (-1850 4325);
PAINT MONO (-1850 4325);
DISPLAY INVISIBLE (-1850 4325);
FORCEPROP 2 LAST CDS_LIB mstr_digital
J 2
(-2000 3875);
PAINT ORANGE (-2000 3875);
DISPLAY INVISIBLE (-2000 3875);
FORCEPROP 2 LAST SEC_TYPE TSSOPLF
J 2
(-1850 4325);
DISPLAY 1.021277 (-1850 4325);
PAINT ORANGE (-1850 4325);
DISPLAY INVISIBLE (-1850 4325);
FORCEPROP 2 LAST BOM_COST MIO_BIOS_MEM
J 0
(-1850 4400);
DISPLAY 1.021277 (-1850 4400);
PAINT ORANGE (-1850 4400);
DISPLAY INVISIBLE (-1850 4400);
FORCEPROP 1 LAST PACK_TYPE TSSOPLF
J 2
(-1850 4325);
DISPLAY 0.468085 (-1850 4325);
PAINT SKYBLUE (-1850 4325);
DISPLAY INVISIBLE (-1850 4325);
FORCEADD OFFPAGE..4
R 2
(-7325 3950);
FORCEPROP 2 LAST $XR1 154 
J 0
(-7697 3950);
DISPLAY 0.638298 (-7697 3950);
PAINT MONO (-7697 3950);
FORCEPROP 2 LAST $XR0 147 
J 0
(-7577 3950);
DISPLAY 0.638298 (-7577 3950);
PAINT MONO (-7577 3950);
FORCEPROP 1 LAST COMMENT_BODY TRUE
J 2
(-7300 3850);
DISPLAY 0.872340 (-7300 3850);
PAINT GREEN (-7300 3850);
DISPLAY INVISIBLE (-7300 3850);
FORCEPROP 1 LAST OFFPAGE TRUE
J 2
(-7650 3825);
DISPLAY 0.872340 (-7650 3825);
PAINT GREEN (-7650 3825);
DISPLAY INVISIBLE (-7650 3825);
FORCEPROP 2 LAST PATH I76
J 2
(-7525 4000);
DISPLAY 1.021277 (-7525 4000);
PAINT ORANGE (-7525 4000);
DISPLAY INVISIBLE (-7525 4000);
FORCEPROP 2 LAST CDS_LIB mstr_standard
J 2
(-7325 3950);
PAINT ORANGE (-7325 3950);
DISPLAY INVISIBLE (-7325 3950);
FORCEADD OFFPAGE..4
R 2
(-7325 3900);
FORCEPROP 2 LAST $XR1 184 
J 0
(-7697 3900);
DISPLAY 0.638298 (-7697 3900);
PAINT MONO (-7697 3900);
FORCEPROP 2 LAST $XR0 121 
J 0
(-7577 3900);
DISPLAY 0.638298 (-7577 3900);
PAINT MONO (-7577 3900);
FORCEPROP 1 LAST COMMENT_BODY TRUE
J 2
(-7300 3800);
DISPLAY 0.872340 (-7300 3800);
PAINT GREEN (-7300 3800);
DISPLAY INVISIBLE (-7300 3800);
FORCEPROP 1 LAST OFFPAGE TRUE
J 2
(-7650 3775);
DISPLAY 0.872340 (-7650 3775);
PAINT GREEN (-7650 3775);
DISPLAY INVISIBLE (-7650 3775);
FORCEPROP 2 LAST PATH I77
J 2
(-7650 3950);
DISPLAY 1.021277 (-7650 3950);
PAINT ORANGE (-7650 3950);
DISPLAY INVISIBLE (-7650 3950);
FORCEPROP 2 LAST CDS_LIB mstr_standard
J 2
(-7325 3900);
PAINT ORANGE (-7325 3900);
DISPLAY INVISIBLE (-7325 3900);
FORCEADD OFFPAGE..4
R 2
(-7325 3850);
FORCEPROP 2 LAST $XR0 144 
J 0
(-7577 3850);
DISPLAY 0.638298 (-7577 3850);
PAINT MONO (-7577 3850);
FORCEPROP 1 LAST COMMENT_BODY TRUE
J 2
(-7300 3750);
DISPLAY 0.872340 (-7300 3750);
PAINT GREEN (-7300 3750);
DISPLAY INVISIBLE (-7300 3750);
FORCEPROP 1 LAST OFFPAGE TRUE
J 2
(-7650 3725);
DISPLAY 0.872340 (-7650 3725);
PAINT GREEN (-7650 3725);
DISPLAY INVISIBLE (-7650 3725);
FORCEPROP 2 LAST PATH I78
J 2
(-7525 3900);
DISPLAY 1.021277 (-7525 3900);
PAINT ORANGE (-7525 3900);
DISPLAY INVISIBLE (-7525 3900);
FORCEPROP 2 LAST CDS_LIB mstr_standard
J 2
(-7325 3850);
PAINT ORANGE (-7325 3850);
DISPLAY INVISIBLE (-7325 3850);
FORCEADD OFFPAGE..4
R 2
(-7325 3800);
FORCEPROP 2 LAST $XR3 184 
J 0
(-7937 3800);
DISPLAY 0.638298 (-7937 3800);
PAINT MONO (-7937 3800);
FORCEPROP 2 LAST $XR2 125 
J 0
(-7817 3800);
DISPLAY 0.638298 (-7817 3800);
PAINT MONO (-7817 3800);
FORCEPROP 2 LAST $XR1 121 
J 0
(-7697 3800);
DISPLAY 0.638298 (-7697 3800);
PAINT MONO (-7697 3800);
FORCEPROP 2 LAST $XR0 111 
J 0
(-7577 3800);
DISPLAY 0.638298 (-7577 3800);
PAINT MONO (-7577 3800);
FORCEPROP 1 LAST COMMENT_BODY TRUE
J 2
(-7300 3700);
DISPLAY 0.872340 (-7300 3700);
PAINT GREEN (-7300 3700);
DISPLAY INVISIBLE (-7300 3700);
FORCEPROP 1 LAST OFFPAGE TRUE
J 2
(-7650 3675);
DISPLAY 0.872340 (-7650 3675);
PAINT GREEN (-7650 3675);
DISPLAY INVISIBLE (-7650 3675);
FORCEPROP 2 LAST PATH I79
J 2
(-7650 3850);
DISPLAY 1.021277 (-7650 3850);
PAINT ORANGE (-7650 3850);
DISPLAY INVISIBLE (-7650 3850);
FORCEPROP 2 LAST CDS_LIB mstr_standard
J 2
(-7325 3800);
PAINT ORANGE (-7325 3800);
DISPLAY INVISIBLE (-7325 3800);
FORCEADD OFFPAGE..2
R 2
(-7325 3550);
FORCEPROP 2 LAST $XR0 144 
J 0
(-7580 3550);
DISPLAY 0.638298 (-7580 3550);
PAINT MONO (-7580 3550);
FORCEPROP 1 LAST COMMENT_BODY TRUE
J 2
(-7280 3455);
DISPLAY 0.872340 (-7280 3455);
PAINT GREEN (-7280 3455);
DISPLAY INVISIBLE (-7280 3455);
FORCEPROP 1 LAST OFFPAGE TRUE
J 2
(-7650 3425);
DISPLAY 0.872340 (-7650 3425);
PAINT GREEN (-7650 3425);
DISPLAY INVISIBLE (-7650 3425);
FORCEPROP 2 LAST PATH I81
J 2
(-7525 3600);
DISPLAY 1.021277 (-7525 3600);
PAINT ORANGE (-7525 3600);
DISPLAY INVISIBLE (-7525 3600);
FORCEPROP 2 LAST CDS_LIB mstr_standard
J 2
(-7325 3550);
PAINT ORANGE (-7325 3550);
DISPLAY INVISIBLE (-7325 3550);
FORCEADD OFFPAGE..4
R 2
(-7325 3750);
FORCEPROP 2 LAST $XR0 144 
J 0
(-7577 3750);
DISPLAY 0.638298 (-7577 3750);
PAINT MONO (-7577 3750);
FORCEPROP 1 LAST COMMENT_BODY TRUE
J 2
(-7300 3650);
DISPLAY 0.872340 (-7300 3650);
PAINT GREEN (-7300 3650);
DISPLAY INVISIBLE (-7300 3650);
FORCEPROP 1 LAST OFFPAGE TRUE
J 2
(-7650 3625);
DISPLAY 0.872340 (-7650 3625);
PAINT GREEN (-7650 3625);
DISPLAY INVISIBLE (-7650 3625);
FORCEPROP 2 LAST PATH I82
J 2
(-7525 3800);
DISPLAY 1.021277 (-7525 3800);
PAINT ORANGE (-7525 3800);
DISPLAY INVISIBLE (-7525 3800);
FORCEPROP 2 LAST CDS_LIB mstr_standard
J 2
(-7325 3750);
PAINT ORANGE (-7325 3750);
DISPLAY INVISIBLE (-7325 3750);
FORCEADD OFFPAGE..4
R 2
(-7325 3700);
FORCEPROP 2 LAST $XR0 121 
J 0
(-7577 3700);
DISPLAY 0.638298 (-7577 3700);
PAINT MONO (-7577 3700);
FORCEPROP 1 LAST COMMENT_BODY TRUE
J 2
(-7300 3600);
DISPLAY 0.872340 (-7300 3600);
PAINT GREEN (-7300 3600);
DISPLAY INVISIBLE (-7300 3600);
FORCEPROP 1 LAST OFFPAGE TRUE
J 2
(-7650 3575);
DISPLAY 0.872340 (-7650 3575);
PAINT GREEN (-7650 3575);
DISPLAY INVISIBLE (-7650 3575);
FORCEPROP 2 LAST PATH I83
J 2
(-7650 3750);
DISPLAY 1.021277 (-7650 3750);
PAINT ORANGE (-7650 3750);
DISPLAY INVISIBLE (-7650 3750);
FORCEPROP 2 LAST CDS_LIB mstr_standard
J 2
(-7325 3700);
PAINT ORANGE (-7325 3700);
DISPLAY INVISIBLE (-7325 3700);
FORCEADD OFFPAGE..4
R 2
(-7325 3650);
FORCEPROP 2 LAST $XR0 144 
J 0
(-7577 3650);
DISPLAY 0.638298 (-7577 3650);
PAINT MONO (-7577 3650);
FORCEPROP 1 LAST COMMENT_BODY TRUE
J 2
(-7300 3550);
DISPLAY 0.872340 (-7300 3550);
PAINT GREEN (-7300 3550);
DISPLAY INVISIBLE (-7300 3550);
FORCEPROP 1 LAST OFFPAGE TRUE
J 2
(-7650 3525);
DISPLAY 0.872340 (-7650 3525);
PAINT GREEN (-7650 3525);
DISPLAY INVISIBLE (-7650 3525);
FORCEPROP 2 LAST PATH I84
J 2
(-7525 3700);
DISPLAY 1.021277 (-7525 3700);
PAINT ORANGE (-7525 3700);
DISPLAY INVISIBLE (-7525 3700);
FORCEPROP 2 LAST CDS_LIB mstr_standard
J 2
(-7325 3650);
PAINT ORANGE (-7325 3650);
DISPLAY INVISIBLE (-7325 3650);
FORCEADD GND..1
(-5625 3325);
FORCEPROP 3 LASTPIN (-5625 3375) SIG_NAME GND\g
J 0
(-5615 3385);
DISPLAY 0.659574 (-5615 3385);
PAINT MONO (-5615 3385);
DISPLAY INVISIBLE (-5615 3385);
FORCEPROP 1 LAST HDL_POWER GND
J 0
(-5625 3475);
DISPLAY 0.872340 (-5625 3475);
PAINT GREEN (-5625 3475);
DISPLAY INVISIBLE (-5625 3475);
FORCEPROP 1 LAST BODY_TYPE PLUMBING
J 0
(-5670 3282);
DISPLAY 0.340426 (-5670 3282);
PAINT GREEN (-5670 3282);
DISPLAY INVISIBLE (-5670 3282);
FORCEPROP 1 LAST PATH I85
J 0
(-5550 3325);
DISPLAY 0.872340 (-5550 3325);
PAINT AQUA (-5550 3325);
DISPLAY INVISIBLE (-5550 3325);
FORCEPROP 1 LAST SIZE 1B
J 0
(-5550 3275);
DISPLAY 0.872340 (-5550 3275);
PAINT AQUA (-5550 3275);
DISPLAY INVISIBLE (-5550 3275);
FORCEPROP 2 LAST CDS_LIB mstr_symbols
J 0
(-5625 3325);
PAINT ORANGE (-5625 3325);
DISPLAY INVISIBLE (-5625 3325);
FORCEPROP 1 LAST VOLTAGE 0.0V
J 0
(-5670 3282);
DISPLAY 0.340426 (-5670 3282);
PAINT SKYBLUE (-5670 3282);
DISPLAY INVISIBLE (-5670 3282);
FORCEADD GND..1
(-6175 3325);
FORCEPROP 3 LASTPIN (-6175 3375) SIG_NAME GND\g
J 0
(-6165 3385);
DISPLAY 0.659574 (-6165 3385);
PAINT MONO (-6165 3385);
DISPLAY INVISIBLE (-6165 3385);
FORCEPROP 1 LAST HDL_POWER GND
J 0
(-6175 3475);
DISPLAY 0.872340 (-6175 3475);
PAINT GREEN (-6175 3475);
DISPLAY INVISIBLE (-6175 3475);
FORCEPROP 1 LAST BODY_TYPE PLUMBING
J 0
(-6220 3282);
DISPLAY 0.340426 (-6220 3282);
PAINT GREEN (-6220 3282);
DISPLAY INVISIBLE (-6220 3282);
FORCEPROP 1 LAST PATH I86
J 0
(-6100 3325);
DISPLAY 0.872340 (-6100 3325);
PAINT AQUA (-6100 3325);
DISPLAY INVISIBLE (-6100 3325);
FORCEPROP 1 LAST SIZE 1B
J 0
(-6100 3275);
DISPLAY 0.872340 (-6100 3275);
PAINT AQUA (-6100 3275);
DISPLAY INVISIBLE (-6100 3275);
FORCEPROP 2 LAST CDS_LIB mstr_symbols
J 0
(-6175 3325);
PAINT ORANGE (-6175 3325);
DISPLAY INVISIBLE (-6175 3325);
FORCEPROP 1 LAST VOLTAGE 0.0V
J 0
(-6220 3282);
DISPLAY 0.340426 (-6220 3282);
PAINT SKYBLUE (-6220 3282);
DISPLAY INVISIBLE (-6220 3282);
FORCEADD OFFPAGE..5
R 2
(-950 4075);
FORCEPROP 2 LAST $XR0 153 
J 0
(-761 4075);
DISPLAY 0.638298 (-761 4075);
PAINT MONO (-761 4075);
FORCEPROP 1 LAST COMMENT_BODY TRUE
J 2
(-1050 4000);
DISPLAY 0.872340 (-1050 4000);
PAINT GREEN (-1050 4000);
DISPLAY INVISIBLE (-1050 4000);
FORCEPROP 1 LAST OFFPAGE TRUE
J 2
(-1275 3950);
DISPLAY 0.872340 (-1275 3950);
PAINT GREEN (-1275 3950);
DISPLAY INVISIBLE (-1275 3950);
FORCEPROP 2 LAST PATH I87
J 2
(-700 4125);
DISPLAY 1.021277 (-700 4125);
PAINT ORANGE (-700 4125);
DISPLAY INVISIBLE (-700 4125);
FORCEPROP 2 LAST CDS_LIB mstr_standard
J 2
(-950 4075);
PAINT ORANGE (-950 4075);
DISPLAY INVISIBLE (-950 4075);
FORCEADD OFFPAGE..5
R 2
(-950 3975);
FORCEPROP 2 LAST $XR0 153 
J 0
(-761 3975);
DISPLAY 0.638298 (-761 3975);
PAINT MONO (-761 3975);
FORCEPROP 1 LAST COMMENT_BODY TRUE
J 2
(-1050 3900);
DISPLAY 0.872340 (-1050 3900);
PAINT GREEN (-1050 3900);
DISPLAY INVISIBLE (-1050 3900);
FORCEPROP 1 LAST OFFPAGE TRUE
J 2
(-1275 3850);
DISPLAY 0.872340 (-1275 3850);
PAINT GREEN (-1275 3850);
DISPLAY INVISIBLE (-1275 3850);
FORCEPROP 2 LAST PATH I88
J 2
(-700 4025);
DISPLAY 1.021277 (-700 4025);
PAINT ORANGE (-700 4025);
DISPLAY INVISIBLE (-700 4025);
FORCEPROP 2 LAST CDS_LIB mstr_standard
J 2
(-950 3975);
PAINT ORANGE (-950 3975);
DISPLAY INVISIBLE (-950 3975);
FORCEADD OFFPAGE..4
R 2
(-3775 4125);
FORCEPROP 2 LAST $XR1 154 
J 0
(-4147 4125);
DISPLAY 0.638298 (-4147 4125);
PAINT MONO (-4147 4125);
FORCEPROP 2 LAST $XR0 147 
J 0
(-4027 4125);
DISPLAY 0.638298 (-4027 4125);
PAINT MONO (-4027 4125);
FORCEPROP 1 LAST COMMENT_BODY TRUE
J 2
(-3750 4025);
DISPLAY 0.872340 (-3750 4025);
PAINT GREEN (-3750 4025);
DISPLAY INVISIBLE (-3750 4025);
FORCEPROP 1 LAST OFFPAGE TRUE
J 2
(-4100 4000);
DISPLAY 0.872340 (-4100 4000);
PAINT GREEN (-4100 4000);
DISPLAY INVISIBLE (-4100 4000);
FORCEPROP 2 LAST CDS_LIB mstr_standard
J 2
(-3775 4125);
PAINT ORANGE (-3775 4125);
DISPLAY INVISIBLE (-3775 4125);
FORCEPROP 2 LAST PATH I89
J 2
(-3975 4175);
DISPLAY 1.021277 (-3975 4175);
PAINT ORANGE (-3975 4175);
DISPLAY INVISIBLE (-3975 4175);
FORCEADD OFFPAGE..4
R 2
(-3775 4075);
FORCEPROP 2 LAST $XR2 125 
J 0
(-4267 4075);
DISPLAY 0.638298 (-4267 4075);
PAINT MONO (-4267 4075);
FORCEPROP 2 LAST $XR1 121 
J 0
(-4147 4075);
DISPLAY 0.638298 (-4147 4075);
PAINT MONO (-4147 4075);
FORCEPROP 2 LAST $XR0 111 
J 0
(-4027 4075);
DISPLAY 0.638298 (-4027 4075);
PAINT MONO (-4027 4075);
FORCEPROP 1 LAST COMMENT_BODY TRUE
J 2
(-3750 3975);
DISPLAY 0.872340 (-3750 3975);
PAINT GREEN (-3750 3975);
DISPLAY INVISIBLE (-3750 3975);
FORCEPROP 1 LAST OFFPAGE TRUE
J 2
(-4100 3950);
DISPLAY 0.872340 (-4100 3950);
PAINT GREEN (-4100 3950);
DISPLAY INVISIBLE (-4100 3950);
FORCEPROP 2 LAST CDS_LIB mstr_standard
J 2
(-3775 4075);
PAINT ORANGE (-3775 4075);
DISPLAY INVISIBLE (-3775 4075);
FORCEPROP 2 LAST PATH I90
J 2
(-4225 4125);
DISPLAY 1.021277 (-4225 4125);
PAINT ORANGE (-4225 4125);
DISPLAY INVISIBLE (-4225 4125);
FORCEADD OFFPAGE..4
R 2
(-3775 3975);
FORCEPROP 2 LAST $XR1 125 
J 0
(-4147 3975);
DISPLAY 0.638298 (-4147 3975);
PAINT MONO (-4147 3975);
FORCEPROP 2 LAST $XR0 121 
J 0
(-4027 3975);
DISPLAY 0.638298 (-4027 3975);
PAINT MONO (-4027 3975);
FORCEPROP 1 LAST COMMENT_BODY TRUE
J 2
(-3750 3875);
DISPLAY 0.872340 (-3750 3875);
PAINT GREEN (-3750 3875);
DISPLAY INVISIBLE (-3750 3875);
FORCEPROP 1 LAST OFFPAGE TRUE
J 2
(-4100 3850);
DISPLAY 0.872340 (-4100 3850);
PAINT GREEN (-4100 3850);
DISPLAY INVISIBLE (-4100 3850);
FORCEPROP 2 LAST CDS_LIB mstr_standard
J 2
(-3775 3975);
PAINT ORANGE (-3775 3975);
DISPLAY INVISIBLE (-3775 3975);
FORCEPROP 2 LAST PATH I91
J 2
(-4100 4025);
DISPLAY 1.021277 (-4100 4025);
PAINT ORANGE (-4100 4025);
DISPLAY INVISIBLE (-4100 4025);
FORCEADD RES..1
(-3200 3975);
FORCEPROP 1 LASTPIN (-3100 3975) $PN 2
J 0
(-3138 3987);
DISPLAY 0.617021 (-3138 3987);
PAINT ORANGE (-3138 3987);
FORCEPROP 1 LAST LOCATION R2T2
J 0
(-3450 4025);
DISPLAY 0.617021 (-3450 4025);
PAINT AQUA (-3450 4025);
FORCEPROP 1 LAST VALUE 0.0
J 0
(-3300 4025);
DISPLAY 0.617021 (-3300 4025);
PAINT SKYBLUE (-3300 4025);
FORCEPROP 1 LASTPIN (-3300 3975) $PN 1
J 0
(-3288 3987);
DISPLAY 0.617021 (-3288 3987);
PAINT ORANGE (-3288 3987);
FORCEPROP 1 LAST TOLERANCE 5%
J 0
(-3200 4025);
DISPLAY 0.617021 (-3200 4025);
PAINT SKYBLUE (-3200 4025);
FORCEPROP 1 LAST WATTAGE 1/16W
J 0
(-3100 4025);
DISPLAY 0.617021 (-3100 4025);
PAINT SKYBLUE (-3100 4025);
FORCEPROP 1 LAST MATERIAL CHIP
J 0
(-3450 3975);
DISPLAY 0.617021 (-3450 3975);
PAINT SKYBLUE (-3450 3975);
FORCEPROP 1 LAST PACK_TYPE 0402
J 0
(-2950 4025);
DISPLAY 0.617021 (-2950 4025);
PAINT SKYBLUE (-2950 4025);
FORCEPROP 1 LAST PART_NUMBER G21497-005
J 0
(-3100 3975);
DISPLAY 0.617021 (-3100 3975);
PAINT BLUE (-3100 3975);
FORCEPROP 2 LAST SEC_TYPE 0402
J 0
(-3250 4175);
DISPLAY 1.021277 (-3250 4175);
PAINT ORANGE (-3250 4175);
DISPLAY INVISIBLE (-3250 4175);
FORCEPROP 2 LAST CDS_LIB mstr_discrete
J 0
(-3200 3975);
PAINT ORANGE (-3200 3975);
DISPLAY INVISIBLE (-3200 3975);
FORCEPROP 2 LAST BOM_COST MIO_BIOS_MEM
J 0
(-3000 4025);
DISPLAY 1.021277 (-3000 4025);
PAINT ORANGE (-3000 4025);
DISPLAY INVISIBLE (-3000 4025);
FORCEPROP 2 LAST SEC 1
J 0
(-3250 4175);
PAINT MONO (-3250 4175);
DISPLAY INVISIBLE (-3250 4175);
FORCEPROP 2 LAST CDS_LOCATION R2T2
J 0
(-3250 3825);
DISPLAY 0.617021 (-3250 3825);
PAINT AQUA (-3250 3825);
DISPLAY INVISIBLE (-3250 3825);
FORCEPROP 1 LAST PATH I92
J 0
(-3250 4125);
DISPLAY 0.978723 (-3250 4125);
PAINT WHITE (-3250 4125);
DISPLAY INVISIBLE (-3250 4125);
FORCEPROP 2 LAST ROOM SB_BMC_SPI_MUX
J 0
(-3000 3975);
DISPLAY 1.021277 (-3000 3975);
PAINT ORANGE (-3000 3975);
DISPLAY INVISIBLE (-3000 3975);
FORCEADD RES..1
(-3200 4075);
FORCEPROP 1 LAST LOCATION R2R12
J 0
(-3450 4150);
DISPLAY 0.617021 (-3450 4150);
PAINT AQUA (-3450 4150);
FORCEPROP 1 LASTPIN (-3100 4075) $PN 2
J 0
(-3138 4087);
DISPLAY 0.617021 (-3138 4087);
PAINT ORANGE (-3138 4087);
FORCEPROP 1 LAST PART_NUMBER G21497-005
J 0
(-3100 4075);
DISPLAY 0.617021 (-3100 4075);
PAINT BLUE (-3100 4075);
FORCEPROP 1 LAST TOLERANCE 5%
J 0
(-3200 4150);
DISPLAY 0.617021 (-3200 4150);
PAINT SKYBLUE (-3200 4150);
FORCEPROP 1 LAST MATERIAL CHIP
J 0
(-3450 4075);
DISPLAY 0.617021 (-3450 4075);
PAINT SKYBLUE (-3450 4075);
FORCEPROP 1 LAST PACK_TYPE 0402
J 0
(-2950 4150);
DISPLAY 0.617021 (-2950 4150);
PAINT SKYBLUE (-2950 4150);
FORCEPROP 1 LAST WATTAGE 1/16W
J 0
(-3100 4150);
DISPLAY 0.617021 (-3100 4150);
PAINT SKYBLUE (-3100 4150);
FORCEPROP 1 LAST VALUE 0.0
J 0
(-3300 4150);
DISPLAY 0.617021 (-3300 4150);
PAINT SKYBLUE (-3300 4150);
FORCEPROP 1 LASTPIN (-3300 4075) $PN 1
J 0
(-3288 4087);
DISPLAY 0.617021 (-3288 4087);
PAINT ORANGE (-3288 4087);
FORCEPROP 2 LAST SEC_TYPE 0402
J 0
(-3250 4275);
DISPLAY 1.021277 (-3250 4275);
PAINT ORANGE (-3250 4275);
DISPLAY INVISIBLE (-3250 4275);
FORCEPROP 2 LAST CDS_LIB mstr_discrete
J 0
(-3200 4075);
PAINT ORANGE (-3200 4075);
DISPLAY INVISIBLE (-3200 4075);
FORCEPROP 2 LAST BOM_COST MIO_BIOS_MEM
J 0
(-3250 4225);
DISPLAY 1.021277 (-3250 4225);
PAINT ORANGE (-3250 4225);
DISPLAY INVISIBLE (-3250 4225);
FORCEPROP 2 LAST SEC 1
J 0
(-3250 4275);
PAINT MONO (-3250 4275);
DISPLAY INVISIBLE (-3250 4275);
FORCEPROP 2 LAST CDS_LOCATION R2R12
J 0
(-3250 4125);
DISPLAY 0.617021 (-3250 4125);
PAINT AQUA (-3250 4125);
DISPLAY INVISIBLE (-3250 4125);
FORCEPROP 1 LAST PATH I93
J 0
(-3250 4225);
DISPLAY 0.978723 (-3250 4225);
PAINT WHITE (-3250 4225);
DISPLAY INVISIBLE (-3250 4225);
FORCEPROP 2 LAST ROOM SB_BMC_SPI_MUX
J 0
(-3250 4175);
DISPLAY 1.021277 (-3250 4175);
PAINT ORANGE (-3250 4175);
DISPLAY INVISIBLE (-3250 4175);
FORCEADD CAP_A..1
(-1500 4525);
FORCEPROP 1 LASTPIN (-1500 4425) $PN 2
J 0
(-1490 4405);
DISPLAY 0.617021 (-1490 4405);
PAINT ORANGE (-1490 4405);
FORCEPROP 1 LASTPIN (-1500 4625) $PN 1
J 0
(-1490 4605);
DISPLAY 0.617021 (-1490 4605);
PAINT ORANGE (-1490 4605);
FORCEPROP 1 LAST MATERIAL X7R
J 0
(-1450 4425);
DISPLAY 0.617021 (-1450 4425);
PAINT SKYBLUE (-1450 4425);
FORCEPROP 1 LAST VOLTAGE 16V
J 0
(-1450 4525);
DISPLAY 0.617021 (-1450 4525);
PAINT SKYBLUE (-1450 4525);
FORCEPROP 1 LAST TOLERANCE 10%
J 0
(-1450 4475);
DISPLAY 0.617021 (-1450 4475);
PAINT SKYBLUE (-1450 4475);
FORCEPROP 1 LAST VALUE 0.1UF
J 0
(-1450 4575);
DISPLAY 0.617021 (-1450 4575);
PAINT SKYBLUE (-1450 4575);
FORCEPROP 1 LAST LOCATION C2T1
J 0
(-1450 4625);
DISPLAY 0.617021 (-1450 4625);
PAINT AQUA (-1450 4625);
FORCEPROP 1 LAST PART_NUMBER A36096-030
J 0
(-1450 4375);
DISPLAY 0.617021 (-1450 4375);
PAINT BLUE (-1450 4375);
FORCEPROP 1 LAST PACK_TYPE 0402V
J 0
(-1450 4325);
DISPLAY 0.617021 (-1450 4325);
PAINT SKYBLUE (-1450 4325);
FORCEPROP 2 LAST SEC 1
J 0
(-1450 4725);
DISPLAY 0.680851 (-1450 4725);
PAINT MONO (-1450 4725);
DISPLAY INVISIBLE (-1450 4725);
FORCEPROP 2 LAST SEC_TYPE 0402V
J 0
(-1450 4725);
DISPLAY 1.021277 (-1450 4725);
PAINT ORANGE (-1450 4725);
DISPLAY INVISIBLE (-1450 4725);
FORCEPROP 2 LAST CDS_SEC 1
J 0
(-1450 4675);
PAINT ORANGE (-1450 4675);
DISPLAY INVISIBLE (-1450 4675);
FORCEPROP 2 LAST CDS_LIB dev_discrete
J 0
(-1500 4525);
PAINT ORANGE (-1500 4525);
DISPLAY INVISIBLE (-1500 4525);
FORCEPROP 2 LAST BOM_COST MIO_BIOS_MEM
J 0
(-1450 4725);
DISPLAY 1.021277 (-1450 4725);
PAINT ORANGE (-1450 4725);
DISPLAY INVISIBLE (-1450 4725);
FORCEPROP 2 LAST CDS_LOCATION C2T1
J 0
(-1450 4625);
DISPLAY 0.617021 (-1450 4625);
PAINT AQUA (-1450 4625);
DISPLAY INVISIBLE (-1450 4625);
FORCEPROP 2 LAST ROOM SB_BMC_SPI_MUX
J 0
(-1450 4675);
DISPLAY 1.021277 (-1450 4675);
PAINT ORANGE (-1450 4675);
DISPLAY INVISIBLE (-1450 4675);
FORCEPROP 1 LAST PATH I94
J 0
(-1450 4675);
DISPLAY 0.978723 (-1450 4675);
PAINT WHITE (-1450 4675);
DISPLAY INVISIBLE (-1450 4675);
FORCEADD GND..1
(-1500 4275);
FORCEPROP 3 LASTPIN (-1500 4325) SIG_NAME GND\g
J 0
(-1490 4335);
DISPLAY 0.659574 (-1490 4335);
PAINT MONO (-1490 4335);
DISPLAY INVISIBLE (-1490 4335);
FORCEPROP 1 LAST HDL_POWER GND
J 0
(-1500 4425);
DISPLAY 0.872340 (-1500 4425);
PAINT GREEN (-1500 4425);
DISPLAY INVISIBLE (-1500 4425);
FORCEPROP 1 LAST BODY_TYPE PLUMBING
J 0
(-1545 4232);
DISPLAY 0.340426 (-1545 4232);
PAINT GREEN (-1545 4232);
DISPLAY INVISIBLE (-1545 4232);
FORCEPROP 1 LAST PATH I95
J 0
(-1425 4275);
DISPLAY 0.872340 (-1425 4275);
PAINT AQUA (-1425 4275);
DISPLAY INVISIBLE (-1425 4275);
FORCEPROP 1 LAST SIZE 1B
J 0
(-1425 4225);
DISPLAY 0.872340 (-1425 4225);
PAINT AQUA (-1425 4225);
DISPLAY INVISIBLE (-1425 4225);
FORCEPROP 2 LAST CDS_LIB mstr_symbols
J 0
(-1500 4275);
PAINT ORANGE (-1500 4275);
DISPLAY INVISIBLE (-1500 4275);
FORCEPROP 1 LAST VOLTAGE 0.0V
J 0
(-1545 4232);
DISPLAY 0.340426 (-1545 4232);
PAINT SKYBLUE (-1545 4232);
DISPLAY INVISIBLE (-1545 4232);
FORCEADD P3V3_STBY..1
(-1675 4775);
FORCEPROP 3 LASTPIN (-1675 4725) SIG_NAME P3V3_STBY\g
J 0
(-1665 4735);
DISPLAY 0.659574 (-1665 4735);
PAINT MONO (-1665 4735);
DISPLAY INVISIBLE (-1665 4735);
FORCEPROP 1 LAST HDL_POWER P3V3_STBY
J 0
(-1975 4650);
DISPLAY 0.872340 (-1975 4650);
PAINT ORANGE (-1975 4650);
DISPLAY INVISIBLE (-1975 4650);
FORCEPROP 1 LAST BODY_TYPE PLUMBING
J 0
(-1720 4732);
DISPLAY 0.340426 (-1720 4732);
PAINT GREEN (-1720 4732);
DISPLAY INVISIBLE (-1720 4732);
FORCEPROP 1 LAST PATH I96
J 0
(-1630 4777);
DISPLAY 0.340426 (-1630 4777);
PAINT GREEN (-1630 4777);
DISPLAY INVISIBLE (-1630 4777);
FORCEPROP 1 LAST SIZE 1B
J 0
(-1630 4797);
DISPLAY 0.340426 (-1630 4797);
PAINT GREEN (-1630 4797);
DISPLAY INVISIBLE (-1630 4797);
FORCEPROP 2 LAST CDS_LIB mstr_symbols
J 0
(-1675 4775);
PAINT ORANGE (-1675 4775);
DISPLAY INVISIBLE (-1675 4775);
FORCEPROP 1 LAST VOLTAGE 3.3V
J 0
(-1720 4732);
DISPLAY 0.340426 (-1720 4732);
PAINT SKYBLUE (-1720 4732);
DISPLAY INVISIBLE (-1720 4732);
FORCEADD GND..1
(-2275 3500);
FORCEPROP 3 LASTPIN (-2275 3550) SIG_NAME GND\g
J 0
(-2265 3560);
DISPLAY 0.659574 (-2265 3560);
PAINT MONO (-2265 3560);
DISPLAY INVISIBLE (-2265 3560);
FORCEPROP 1 LAST HDL_POWER GND
J 0
(-2275 3650);
DISPLAY 0.872340 (-2275 3650);
PAINT GREEN (-2275 3650);
DISPLAY INVISIBLE (-2275 3650);
FORCEPROP 1 LAST BODY_TYPE PLUMBING
J 0
(-2320 3457);
DISPLAY 0.340426 (-2320 3457);
PAINT GREEN (-2320 3457);
DISPLAY INVISIBLE (-2320 3457);
FORCEPROP 1 LAST PATH I97
J 0
(-2200 3500);
DISPLAY 0.872340 (-2200 3500);
PAINT AQUA (-2200 3500);
DISPLAY INVISIBLE (-2200 3500);
FORCEPROP 1 LAST SIZE 1B
J 0
(-2200 3450);
DISPLAY 0.872340 (-2200 3450);
PAINT AQUA (-2200 3450);
DISPLAY INVISIBLE (-2200 3450);
FORCEPROP 2 LAST CDS_LIB mstr_symbols
J 0
(-2275 3500);
PAINT ORANGE (-2275 3500);
DISPLAY INVISIBLE (-2275 3500);
FORCEPROP 1 LAST VOLTAGE 0.0V
J 0
(-2320 3457);
DISPLAY 0.340426 (-2320 3457);
PAINT SKYBLUE (-2320 3457);
DISPLAY INVISIBLE (-2320 3457);
FORCEADD GND..1
(-1725 3500);
FORCEPROP 3 LASTPIN (-1725 3550) SIG_NAME GND\g
J 0
(-1715 3560);
DISPLAY 0.659574 (-1715 3560);
PAINT MONO (-1715 3560);
DISPLAY INVISIBLE (-1715 3560);
FORCEPROP 1 LAST HDL_POWER GND
J 0
(-1725 3650);
DISPLAY 0.872340 (-1725 3650);
PAINT GREEN (-1725 3650);
DISPLAY INVISIBLE (-1725 3650);
FORCEPROP 1 LAST BODY_TYPE PLUMBING
J 0
(-1770 3457);
DISPLAY 0.340426 (-1770 3457);
PAINT GREEN (-1770 3457);
DISPLAY INVISIBLE (-1770 3457);
FORCEPROP 1 LAST PATH I98
J 0
(-1650 3500);
DISPLAY 0.872340 (-1650 3500);
PAINT AQUA (-1650 3500);
DISPLAY INVISIBLE (-1650 3500);
FORCEPROP 1 LAST SIZE 1B
J 0
(-1650 3450);
DISPLAY 0.872340 (-1650 3450);
PAINT AQUA (-1650 3450);
DISPLAY INVISIBLE (-1650 3450);
FORCEPROP 2 LAST CDS_LIB mstr_symbols
J 0
(-1725 3500);
PAINT ORANGE (-1725 3500);
DISPLAY INVISIBLE (-1725 3500);
FORCEPROP 1 LAST VOLTAGE 0.0V
J 0
(-1770 3457);
DISPLAY 0.340426 (-1770 3457);
PAINT SKYBLUE (-1770 3457);
DISPLAY INVISIBLE (-1770 3457);
FORCEADD TTL1G32_A..1
(-2275 1875);
FORCEPROP 1 LAST PART_NUMBER E60229-001
J 0
(-2375 1725);
DISPLAY 0.617021 (-2375 1725);
PAINT BLUE (-2375 1725);
FORCEPROP 2 LASTPIN (-2125 1875) $PN 4
J 0
(-2115 1885);
DISPLAY 0.617021 (-2115 1885);
PAINT ORANGE (-2115 1885);
FORCEPROP 2 LASTPIN (-2425 1825) $PN 2
J 2
(-2435 1835);
DISPLAY 0.617021 (-2435 1835);
PAINT ORANGE (-2435 1835);
FORCEPROP 2 LASTPIN (-2425 1925) $PN 1
J 2
(-2435 1935);
DISPLAY 0.617021 (-2435 1935);
PAINT ORANGE (-2435 1935);
FORCEPROP 1 LAST MATERIAL IC
J 0
(-2375 2050);
DISPLAY 0.617021 (-2375 2050);
PAINT SKYBLUE (-2375 2050);
FORCEPROP 1 LAST VALUE 74LVC1G32
J 0
(-2375 2000);
DISPLAY 0.617021 (-2375 2000);
PAINT SKYBLUE (-2375 2000);
FORCEPROP 1 LAST LOCATION U2T3
J 0
(-2375 2100);
DISPLAY 0.617021 (-2375 2100);
PAINT AQUA (-2375 2100);
FORCEPROP 1 LAST POWER_GROUP VCC=P3V3_STBY;GND=GND
J 0
(-2375 1675);
DISPLAY 0.617021 (-2375 1675);
PAINT ORANGE (-2375 1675);
FORCEPROP 0 LAST GROUP NI_BIOS_ROM2
J 0
(-2382 1624);
DISPLAY 0.638298 (-2382 1624);
PAINT BROWN (-2382 1624);
DISPLAY BOTH (-2382 1624);
FORCEPROP 2 LAST ROOM SB_BMC_SPI_MUX
J 0
(-2375 2150);
DISPLAY 1.021277 (-2375 2150);
PAINT ORANGE (-2375 2150);
DISPLAY INVISIBLE (-2375 2150);
FORCEPROP 1 LAST PATH I99
J 0
(-1925 2050);
DISPLAY 0.978723 (-1925 2050);
PAINT ORANGE (-1925 2050);
DISPLAY INVISIBLE (-1925 2050);
FORCEPROP 2 LAST CDS_LOCATION U2T3
J 0
(-2375 2100);
DISPLAY 0.617021 (-2375 2100);
PAINT AQUA (-2375 2100);
DISPLAY INVISIBLE (-2375 2100);
FORCEPROP 2 LAST SEC 1
J 0
(-2375 2150);
DISPLAY 0.680851 (-2375 2150);
PAINT MONO (-2375 2150);
DISPLAY INVISIBLE (-2375 2150);
FORCEPROP 2 LAST CDS_LIB mstr_ttl
J 0
(-2275 1875);
PAINT ORANGE (-2275 1875);
DISPLAY INVISIBLE (-2275 1875);
FORCEPROP 2 LAST SEC_TYPE SOT
J 0
(-2375 2150);
DISPLAY 1.021277 (-2375 2150);
PAINT ORANGE (-2375 2150);
DISPLAY INVISIBLE (-2375 2150);
FORCEPROP 2 LAST BOM_COST MIO_BIOS_MEM
J 0
(-2375 2200);
DISPLAY 1.021277 (-2375 2200);
PAINT ORANGE (-2375 2200);
DISPLAY INVISIBLE (-2375 2200);
FORCEPROP 1 LAST PACK_TYPE SOT
J 0
(-2375 2150);
DISPLAY 0.978723 (-2375 2150);
PAINT SKYBLUE (-2375 2150);
DISPLAY INVISIBLE (-2375 2150);
FORCEADD INTEL_CORP_BPAGE..1
(0 0);
FORCEPROP 1 LAST CDS_CON_LAST_MODIFIED Fri Jun 16 17:48:58 2017
J 0
(-1425 325);
DISPLAY 1.361702 (-1425 325);
PAINT GREEN (-1425 325);
DISPLAY INVISIBLE (-1425 325);
FORCEPROP 1 LAST CUSTOM_TXT_CDS <CURRENT_DESIGN_SHEET> OF <TOTAL_DESIGN_SHEETS>
J 0
(-500 25);
PAINT ORANGE (-500 25);
FORCEPROP 1 LAST CUSTOM_TXT_CDS <CON_LAST_MODIFIED>
J 0
(-4000 100);
PAINT ORANGE (-4000 100);
FORCEPROP 2 LAST CUSTOM_TXT_CDS <XR_PAGE_TITLE>
J 0
(-7890 5250);
DISPLAY 0.638298 (-7890 5250);
PAINT PINK (-7890 5250);
DISPLAY INVISIBLE (-7890 5250);
FORCEPROP 1 LAST SCH_TITLE PCH AND BMC SHARED SPI FLASH MUX
J 0
(-7950 50);
DISPLAY 1.212766 (-7950 50);
PAINT ORANGE (-7950 50);
FORCEPROP 1 LAST COMMENT_BODY TRUE
J 0
(12 12);
DISPLAY 0.617021 (12 12);
PAINT GREEN (12 12);
DISPLAY INVISIBLE (12 12);
FORCEPROP 2 LAST PAGE_BORDER TRUE
J 0
(-7890 5250);
DISPLAY 0.851064 (-7890 5250);
PAINT PINK (-7890 5250);
DISPLAY INVISIBLE (-7890 5250);
FORCEPROP 2 LAST CDS_LIB mstr_symbols
J 0
(0 0);
DISPLAY 1.361702 (0 0);
PAINT ORANGE (0 0);
DISPLAY INVISIBLE (0 0);
FORCEPROP 2 LAST CDS_XR_PAGE_TITLE CR-154 : @BASEBOARD_FAB2_LIB.BASEBOARD_FAB2(SCH_1):PAGE154
J 0
(-7890 5250);
DISPLAY 0.638298 (-7890 5250);
PAINT PINK (-7890 5250);
DISPLAY INVISIBLE (-7890 5250);
FORCEADD CAD_NOTE..1
(-850 1550);
FORCEPROP 0 LAST L2 ON 74LVC1G32
J 2
(-600 1350);
DISPLAY 1.021277 (-600 1350);
PAINT ORANGE (-600 1350);
FORCEPROP 0 LAST L1 PLACE 0.1UF CAP NEXT TO VCC PIN
J 2
(-600 1425);
DISPLAY 1.021277 (-600 1425);
PAINT ORANGE (-600 1425);
FORCEPROP 1 LAST COMMENT_BODY TRUE
J 0
(-825 1650);
DISPLAY 0.978723 (-825 1650);
PAINT ORANGE (-825 1650);
DISPLAY INVISIBLE (-825 1650);
FORCEPROP 2 LAST CDS_LIB mstr_symbols
J 0
(-850 1550);
PAINT ORANGE (-850 1550);
DISPLAY INVISIBLE (-850 1550);
FORCEADD DESIGN_NOTE..1
(-5475 2800);
FORCEPROP 0 LAST L4 TO CONNECT BMC TO SPI FLASH
J 0
(-5675 2450);
DISPLAY 0.808511 (-5675 2450);
PAINT ORANGE (-5675 2450);
FORCEPROP 0 LAST L3 BMC SKU, THE BMC CAN PULL THIS NET HIGH
J 0
(-5675 2525);
DISPLAY 0.808511 (-5675 2525);
PAINT ORANGE (-5675 2525);
FORCEPROP 0 LAST L2 SO THAT PCH IS DEFAULT BUS AND FOR
J 0
(-5675 2600);
DISPLAY 0.808511 (-5675 2600);
PAINT ORANGE (-5675 2600);
FORCEPROP 0 LAST L1 FM_BIOS_SPI_BMC_CTRL NET SHOULD BE PULLED DOWN
J 0
(-5675 2675);
DISPLAY 0.808511 (-5675 2675);
PAINT ORANGE (-5675 2675);
FORCEPROP 1 LAST COMMENT_BODY TRUE
J 0
(-5450 2900);
DISPLAY 0.978723 (-5450 2900);
PAINT ORANGE (-5450 2900);
DISPLAY INVISIBLE (-5450 2900);
FORCEPROP 2 LAST CDS_LIB mstr_symbols
J 0
(-5475 2800);
PAINT MONO (-5475 2800);
DISPLAY INVISIBLE (-5475 2800);
FORCEADD CAD_NOTE..1
(-7525 3425);
FORCEPROP 0 LAST L1 PLACE R8F6 CLOSE TO U8F1
J 0
(-7675 3300);
DISPLAY 1.021277 (-7675 3300);
PAINT ORANGE (-7675 3300);
FORCEPROP 1 LAST COMMENT_BODY TRUE
J 0
(-7500 3525);
DISPLAY 0.978723 (-7500 3525);
PAINT ORANGE (-7500 3525);
DISPLAY INVISIBLE (-7500 3525);
FORCEPROP 2 LAST CDS_LIB mstr_symbols
J 0
(-7525 3425);
PAINT ORANGE (-7525 3425);
DISPLAY INVISIBLE (-7525 3425);
FORCEADD CAD_NOTE..1
(-875 2400);
FORCEPROP 0 LAST L2 ON 74LVC1G32
J 2
(-625 2200);
DISPLAY 1.021277 (-625 2200);
PAINT ORANGE (-625 2200);
FORCEPROP 0 LAST L1 PLACE 0.1UF CAP NEXT TO VCC PIN
J 2
(-625 2275);
DISPLAY 1.021277 (-625 2275);
PAINT ORANGE (-625 2275);
FORCEPROP 1 LAST COMMENT_BODY TRUE
J 0
(-850 2500);
DISPLAY 0.978723 (-850 2500);
PAINT ORANGE (-850 2500);
DISPLAY INVISIBLE (-850 2500);
FORCEPROP 2 LAST CDS_LIB mstr_symbols
J 0
(-875 2400);
PAINT ORANGE (-875 2400);
DISPLAY INVISIBLE (-875 2400);
WIRE 16 -1 (-3100 1325)(-3100 1375);
WIRE 16 -1 (-3100 2400)(-3100 2300);
WIRE 16 -1 (-3775 1850)(-3775 1975);
WIRE 16 -1 (-5575 4550)(-5575 4500);
WIRE 16 -1 (-5575 4500)(-5400 4500);
WIRE 16 -1 (-5575 4500)(-5575 4000);
WIRE 16 -1 (-5575 4000)(-5700 4000);
WIRE 16 -1 (-5400 4450)(-5400 4500);
WIRE 16 -1 (-6250 2500)(-6250 2650);
WIRE 16 -1 (-5400 4150)(-5400 4250);
WIRE 16 -1 (-375 2475)(-375 2325);
WIRE 16 -1 (-375 1975)(-375 2125);
WIRE 16 -1 (-375 1650)(-375 1575);
WIRE 16 -1 (-375 1300)(-375 1375);
WIRE 16 -1 (-3400 1975)(-3400 1850);
WIRE 16 -1 (-5625 3375)(-5625 3500);
WIRE 16 -1 (-5625 3500)(-5700 3500);
WIRE 16 -1 (-6175 3375)(-6175 4000);
WIRE 16 -1 (-6175 4000)(-6100 4000);
WIRE 16 -1 (-1500 4325)(-1500 4425);
WIRE 16 -1 (-1675 4725)(-1675 4675);
WIRE 16 -1 (-1675 4675)(-1500 4675);
WIRE 16 -1 (-1675 4675)(-1675 4175);
WIRE 16 -1 (-1675 4175)(-1800 4175);
WIRE 16 -1 (-1500 4625)(-1500 4675);
WIRE 16 -1 (-2275 3550)(-2275 4175);
WIRE 16 -1 (-2275 4175)(-2200 4175);
WIRE 16 -1 (-1725 3550)(-1725 3675);
WIRE 16 -1 (-1725 3675)(-1800 3675);
WIRE 16 -1 (-6300 4450)(-6300 4550);
WIRE 16 -1 (-7600 4550)(-6300 4550);
WIRE 16 -1 (-7600 4450)(-6300 4450);
WIRE 16 -1 (-7600 4450)(-7600 4550);
WIRE 16 -1 (-6300 4550)(-6300 4650);
WIRE 16 -1 (-6300 4350)(-6300 4450);
WIRE 16 -1 (-6300 4350)(-6300 4225);
WIRE 16 -1 (-6300 4650)(-6700 4650);
WIRE 16 -1 (-7600 4450)(-7600 4350);
WIRE 16 -1 (-7600 4350)(-6300 4350);
WIRE 16 -1 (-7600 4650)(-7600 4550);
WIRE 16 -1 (-7350 4650)(-7600 4650);
WIRE 16 -1 (-7600 4225)(-7600 4350);
WIRE 16 -1 (-6700 4650)(-7050 4650);
WIRE 16 -1 (-7050 4650)(-7350 4650);
WIRE 16 -1 (-6700 4650)(-6700 4225);
WIRE 16 -1 (-6700 4225)(-6300 4225);
WIRE 16 -1 (-7050 4225)(-6700 4225);
WIRE 16 -1 (-7050 4650)(-7050 4225);
WIRE 16 -1 (-7600 4225)(-7350 4225);
WIRE 16 -1 (-7350 4650)(-7350 4225);
WIRE 16 -1 (-7350 4225)(-7050 4225);
WIRE 16 -1 (-3475 3300)(-3475 3175);
WIRE 16 -1 (-3475 3175)(-1450 3175);
WIRE 16 -1 (-3475 2925)(-3475 3175);
WIRE 16 -1 (-3475 2925)(-1450 2925);
WIRE 16 -1 (-1450 2925)(-1450 3175);
WIRE 16 -1 (-3475 2750)(-3475 2925);
WIRE 16 -1 (-3475 2600)(-3475 2750);
WIRE 16 -1 (-1450 3175)(-1450 3300);
WIRE 16 -1 (-2825 3300)(-3475 3300);
WIRE 16 -1 (-2200 3300)(-2825 3300);
WIRE 16 -1 (-1450 3300)(-2200 3300);
WIRE 16 -1 (-3475 2600)(-2825 2600);
WIRE 16 -1 (-2825 3300)(-2825 2600);
WIRE 16 -1 (-3475 2750)(-1450 2750);
WIRE 16 -1 (-1450 2750)(-1450 2925);
WIRE 16 -1 (-1450 2600)(-1450 2750);
WIRE 16 -1 (-2825 2600)(-2200 2600);
WIRE 16 -1 (-2200 3300)(-2200 2600);
WIRE 16 -1 (-2200 2600)(-1450 2600);
WIRE 16 -1 (-2125 1150)(-1550 1150);
FORCEPROP 2 LAST SIG_NAME SPI_CS0_SECONDARY_N
J 0
(-2075 1160);
DISPLAY 0.617021 (-2075 1160);
PAINT ORANGE (-2075 1160);
FORCEPROP 2 LASTPROP $XRERR UNIQUE?
J 0
(-2315 1160);
DISPLAY 0.638298 (-2315 1160);
PAINT MONO (-2315 1160);
DISPLAY INVISIBLE (-2315 1160);
WIRE 16 -1 (-1350 1150)(-650 1150);
FORCEPROP 2 LAST SIG_NAME SPI_CS0_SECONDARY_R_N
J 2
(-675 1160);
DISPLAY 0.617021 (-675 1160);
PAINT ORANGE (-675 1160);
WIRE 16 -1 (-7275 3550)(-6100 3550);
FORCEPROP 2 LAST SIG_NAME SPI_BMC_DI
J 0
(-7250 3560);
DISPLAY 0.617021 (-7250 3560);
PAINT ORANGE (-7250 3560);
WIRE 16 -1 (-5700 3700)(-4900 3700);
FORCEPROP 2 LAST SIG_NAME SPI_SWITCH_CS0_N
J 2
(-4900 3710);
DISPLAY 0.617021 (-4900 3710);
PAINT ORANGE (-4900 3710);
WIRE 16 -1 (-5700 3600)(-4900 3600);
FORCEPROP 2 LAST SIG_NAME SPI_SWITCH_MISO
J 2
(-4900 3610);
DISPLAY 0.617021 (-4900 3610);
PAINT ORANGE (-4900 3610);
WIRE 16 -1 (-5700 3900)(-4900 3900);
FORCEPROP 2 LAST SIG_NAME SPI_SWITCH_CLK
J 2
(-4900 3910);
DISPLAY 0.617021 (-4900 3910);
PAINT ORANGE (-4900 3910);
WIRE 16 -1 (-5700 3800)(-4900 3800);
FORCEPROP 2 LAST SIG_NAME SPI_SWITCH_MOSI
J 2
(-4900 3810);
DISPLAY 0.617021 (-4900 3810);
PAINT ORANGE (-4900 3810);
WIRE 16 -1 (-3100 3975)(-2200 3975);
FORCEPROP 2 LAST SIG_NAME SPI_PCH_IO3_R1
J 2
(-2425 3985);
DISPLAY 0.617021 (-2425 3985);
PAINT ORANGE (-2425 3985);
FORCEPROP 2 LASTPROP $XRERR UNIQUE?
J 0
(-2665 3985);
DISPLAY 0.638298 (-2665 3985);
PAINT MONO (-2665 3985);
DISPLAY INVISIBLE (-2665 3985);
WIRE 16 -1 (-3300 3975)(-3725 3975);
FORCEPROP 2 LAST SIG_NAME SPI_PCH_IO3
J 0
(-3710 3985);
DISPLAY 0.617021 (-3710 3985);
PAINT ORANGE (-3710 3985);
WIRE 16 -1 (-3725 4125)(-2200 4125);
FORCEPROP 2 LAST SIG_NAME FM_BIOS_SPI_BMC_CTRL
J 2
(-2400 4135);
DISPLAY 0.617021 (-2400 4135);
PAINT ORANGE (-2400 4135);
WIRE 16 -1 (-3300 4075)(-3725 4075);
FORCEPROP 2 LAST SIG_NAME SPI_PCH_IO2
J 0
(-3710 4085);
DISPLAY 0.617021 (-3710 4085);
PAINT ORANGE (-3710 4085);
WIRE 16 -1 (-3100 4075)(-2200 4075);
FORCEPROP 2 LAST SIG_NAME SPI_PCH_IO2_R1
J 2
(-2425 4085);
DISPLAY 0.617021 (-2425 4085);
PAINT ORANGE (-2425 4085);
FORCEPROP 2 LASTPROP $XRERR UNIQUE?
J 0
(-2665 4085);
DISPLAY 0.638298 (-2665 4085);
PAINT MONO (-2665 4085);
DISPLAY INVISIBLE (-2665 4085);
WIRE 16 -1 (-2800 3875)(-2200 3875);
FORCEPROP 2 LAST SIG_NAME TP_SPI_SWITCH1_11
J 0
(-2750 3885);
DISPLAY 0.617021 (-2750 3885);
PAINT ORANGE (-2750 3885);
FORCEPROP 2 LASTPROP $XRERR UNIQUE?
J 0
(-3040 3875);
DISPLAY 0.638298 (-3040 3875);
PAINT MONO (-3040 3875);
DISPLAY INVISIBLE (-3040 3875);
WIRE 16 -1 (-2800 3925)(-2200 3925);
FORCEPROP 2 LAST SIG_NAME TP_SPI_SWITCH1_6
J 0
(-2750 3935);
DISPLAY 0.617021 (-2750 3935);
PAINT ORANGE (-2750 3935);
FORCEPROP 2 LASTPROP $XRERR UNIQUE?
J 0
(-3040 3925);
DISPLAY 0.638298 (-3040 3925);
PAINT MONO (-3040 3925);
DISPLAY INVISIBLE (-3040 3925);
WIRE 16 -1 (-2800 4025)(-2200 4025);
FORCEPROP 2 LAST SIG_NAME TP_SPI_SWITCH1_3
J 0
(-2750 4035);
DISPLAY 0.617021 (-2750 4035);
PAINT ORANGE (-2750 4035);
FORCEPROP 2 LASTPROP $XRERR UNIQUE?
J 0
(-3040 4025);
DISPLAY 0.638298 (-3040 4025);
PAINT MONO (-3040 4025);
DISPLAY INVISIBLE (-3040 4025);
WIRE 16 -1 (-2800 3825)(-2200 3825);
FORCEPROP 2 LAST SIG_NAME TP_SPI_SWITCH1_10
J 0
(-2750 3835);
DISPLAY 0.617021 (-2750 3835);
PAINT ORANGE (-2750 3835);
FORCEPROP 2 LASTPROP $XRERR UNIQUE?
J 0
(-3040 3825);
DISPLAY 0.638298 (-3040 3825);
PAINT MONO (-3040 3825);
DISPLAY INVISIBLE (-3040 3825);
WIRE 16 -1 (-2800 3725)(-2200 3725);
FORCEPROP 2 LAST SIG_NAME TP_SPI_SWITCH1_13
J 0
(-2750 3735);
DISPLAY 0.617021 (-2750 3735);
PAINT ORANGE (-2750 3735);
FORCEPROP 2 LASTPROP $XRERR UNIQUE?
J 0
(-3040 3725);
DISPLAY 0.638298 (-3040 3725);
PAINT MONO (-3040 3725);
DISPLAY INVISIBLE (-3040 3725);
WIRE 16 -1 (-2800 3775)(-2200 3775);
FORCEPROP 2 LAST SIG_NAME TP_SPI_SWITCH1_14
J 0
(-2750 3785);
DISPLAY 0.617021 (-2750 3785);
PAINT ORANGE (-2750 3785);
FORCEPROP 2 LASTPROP $XRERR UNIQUE?
J 0
(-3040 3775);
DISPLAY 0.638298 (-3040 3775);
PAINT MONO (-3040 3775);
DISPLAY INVISIBLE (-3040 3775);
WIRE 16 -1 (-7275 3650)(-6100 3650);
FORCEPROP 2 LAST SIG_NAME SPI_BMC_CS0_N
J 0
(-7260 3660);
DISPLAY 0.680851 (-7260 3660);
PAINT ORANGE (-7260 3660);
WIRE 16 -1 (-7275 3700)(-6100 3700);
FORCEPROP 2 LAST SIG_NAME SPI_PCH_CS0_N
J 0
(-7250 3710);
DISPLAY 0.617021 (-7250 3710);
PAINT ORANGE (-7250 3710);
WIRE 16 -1 (-6825 3600)(-7275 3600);
FORCEPROP 2 LAST SIG_NAME SPI_PCH_MISO
J 0
(-7275 3610);
DISPLAY 0.617021 (-7275 3610);
PAINT ORANGE (-7275 3610);
WIRE 16 -1 (-7275 3750)(-6100 3750);
FORCEPROP 2 LAST SIG_NAME SPI_BMC_DO
J 0
(-7250 3760);
DISPLAY 0.617021 (-7250 3760);
PAINT ORANGE (-7250 3760);
WIRE 16 -1 (-7275 3800)(-6100 3800);
FORCEPROP 2 LAST SIG_NAME SPI_PCH_MOSI
J 0
(-7250 3810);
DISPLAY 0.617021 (-7250 3810);
PAINT ORANGE (-7250 3810);
WIRE 16 -1 (-7275 3950)(-6100 3950);
FORCEPROP 2 LAST SIG_NAME FM_BIOS_SPI_BMC_CTRL
J 0
(-7250 3960);
DISPLAY 0.617021 (-7250 3960);
PAINT ORANGE (-7250 3960);
WIRE 16 -1 (-7275 3900)(-6100 3900);
FORCEPROP 2 LAST SIG_NAME SPI_PCH_CLK
J 0
(-7250 3910);
DISPLAY 0.617021 (-7250 3910);
PAINT ORANGE (-7250 3910);
WIRE 16 -1 (-7275 3850)(-6100 3850);
FORCEPROP 2 LAST SIG_NAME SPI_BMC_CLK
J 0
(-7250 3860);
DISPLAY 0.617021 (-7250 3860);
PAINT ORANGE (-7250 3860);
WIRE 16 -1 (-1800 4075)(-1000 4075);
FORCEPROP 2 LAST SIG_NAME SPI_BIOS_SOCKET_IO2
J 2
(-1000 4085);
DISPLAY 0.617021 (-1000 4085);
PAINT ORANGE (-1000 4085);
WIRE 16 -1 (-1800 3975)(-1000 3975);
FORCEPROP 2 LAST SIG_NAME SPI_BIOS_SOCKET_IO3
J 2
(-1000 3985);
DISPLAY 0.617021 (-1000 3985);
PAINT ORANGE (-1000 3985);
WIRE 16 -1 (-1800 3875)(-1000 3875);
FORCEPROP 2 LAST SIG_NAME TP_SPI_SWITCH1_9
J 2
(-1000 3885);
DISPLAY 0.617021 (-1000 3885);
PAINT ORANGE (-1000 3885);
FORCEPROP 2 LASTPROP $XRERR UNIQUE?
J 0
(-970 3875);
DISPLAY 0.638298 (-970 3875);
PAINT MONO (-970 3875);
DISPLAY INVISIBLE (-970 3875);
WIRE 16 -1 (-6100 3600)(-6625 3600);
FORCEPROP 2 LAST SIG_NAME SPI_PCH_MISO_R
J 2
(-6200 3610);
DISPLAY 0.617021 (-6200 3610);
PAINT ORANGE (-6200 3610);
FORCEPROP 2 LASTPROP $XRERR UNIQUE?
J 0
(-6440 3610);
DISPLAY 0.638298 (-6440 3610);
PAINT MONO (-6440 3610);
DISPLAY INVISIBLE (-6440 3610);
WIRE 16 -1 (-6250 2850)(-6250 3000);
WIRE 16 -1 (-6250 3000)(-5425 3000);
FORCEPROP 2 LAST SIG_NAME FM_BIOS_SPI_BMC_CTRL
J 0
(-6160 3010);
DISPLAY 0.617021 (-6160 3010);
PAINT ORANGE (-6160 3010);
WIRE 16 -1 (-1800 3775)(-1000 3775);
FORCEPROP 2 LAST SIG_NAME TP_SPI_SWITCH1_12
J 2
(-1000 3785);
DISPLAY 0.617021 (-1000 3785);
PAINT ORANGE (-1000 3785);
FORCEPROP 2 LASTPROP $XRERR UNIQUE?
J 0
(-970 3775);
DISPLAY 0.638298 (-970 3775);
PAINT MONO (-970 3775);
DISPLAY INVISIBLE (-970 3775);
WIRE 16 -1 (-1350 1875)(-875 1875);
FORCEPROP 2 LAST SIG_NAME SPI_CS0_PRIMARY_R_N
J 2
(-875 1885);
DISPLAY 0.617021 (-875 1885);
PAINT ORANGE (-875 1885);
WIRE 16 -1 (-3400 1475)(-3300 1475);
WIRE 16 -1 (-3400 1650)(-3400 1475);
WIRE 16 -1 (-3500 1475)(-4425 1475);
WIRE 16 -1 (-3500 1475)(-3400 1475);
WIRE 16 -1 (-3500 1200)(-3500 1475);
FORCEPROP 2 LAST SIG_NAME FM_BACKUP_BIOS_SEL_N
J 0
(-4360 1485);
DISPLAY 0.617021 (-4360 1485);
PAINT ORANGE (-4360 1485);
WIRE 16 -1 (-3500 1200)(-2425 1200);
WIRE 16 -1 (-1550 1875)(-2125 1875);
FORCEPROP 2 LAST SIG_NAME SPI_CS0_PRIMARY_N
J 0
(-2050 1885);
DISPLAY 0.617021 (-2050 1885);
PAINT ORANGE (-2050 1885);
FORCEPROP 2 LASTPROP $XRERR UNIQUE?
J 0
(-2290 1885);
DISPLAY 0.638298 (-2290 1885);
PAINT MONO (-2290 1885);
DISPLAY INVISIBLE (-2290 1885);
WIRE 16 -1 (-4450 1100)(-3775 1100);
FORCEPROP 2 LAST SIG_NAME SPI_SWITCH_CS0_N
J 0
(-4410 1110);
DISPLAY 0.617021 (-4410 1110);
PAINT ORANGE (-4410 1110);
WIRE 16 -1 (-3775 1650)(-3775 1100);
WIRE 16 -1 (-3775 1100)(-2675 1100);
WIRE 16 -1 (-2425 1100)(-2675 1100);
WIRE 16 -1 (-2675 1825)(-2675 1100);
WIRE 16 -1 (-2675 1825)(-2425 1825);
WIRE 16 -1 (-3100 1775)(-3100 1925);
FORCEPROP 2 LAST SIG_NAME FM_DUAL_BIOS_SEL_N
J 0
(-3085 1950);
DISPLAY 0.617021 (-3085 1950);
PAINT ORANGE (-3085 1950);
FORCEPROP 2 LASTPROP $XRERR UNIQUE?
J 0
(-3325 1950);
DISPLAY 0.638298 (-3325 1950);
PAINT MONO (-3325 1950);
DISPLAY INVISIBLE (-3325 1950);
WIRE 16 -1 (-3100 1925)(-2425 1925);
WIRE 16 -1 (-3100 1925)(-3100 2100);
DOT 1 (-6300 4350);
DOT 1 (-3100 1925);
DOT 1 (-2200 3300);
DOT 1 (-3475 2750);
DOT 1 (-3475 3175);
DOT 1 (-1450 3175);
DOT 1 (-2200 2600);
DOT 1 (-2825 3300);
DOT 1 (-6700 4650);
DOT 1 (-6700 4225);
DOT 1 (-7050 4650);
DOT 1 (-6300 4550);
DOT 1 (-6300 4450);
DOT 1 (-7350 4650);
DOT 1 (-7050 4225);
DOT 1 (-7350 4225);
DOT 1 (-7600 4350);
DOT 1 (-1675 4675);
DOT 1 (-5575 4500);
DOT 1 (-3475 2925);
DOT 1 (-2825 2600);
DOT 1 (-1450 2750);
DOT 1 (-1450 2925);
DOT 1 (-7600 4550);
DOT 1 (-3400 1475);
DOT 1 (-7600 4450);
DOT 1 (-3775 1100);
DOT 1 (-2675 1100);
DOT 1 (-3500 1475);
FORCENOTE
FM_BACKUP_BIOS_SEL_N
(-3450 3200) 0;
DISPLAY LEFT (-3450 3200);
DISPLAY 0.808511 (-3450 3200);
PAINT PURPLE (-3450 3200);
FORCENOTE
PI3B3257A TRUTH TABLE
(-7600 4725) 0;
DISPLAY LEFT (-7600 4725);
DISPLAY 1.021277 (-7600 4725);
PAINT PURPLE (-7600 4725);
FORCENOTE
L
(-7525 4275) 0;
DISPLAY LEFT (-7525 4275);
DISPLAY 1.021277 (-7525 4275);
PAINT PURPLE (-7525 4275);
FORCENOTE
H
(-2575 2650) 0;
DISPLAY LEFT (-2575 2650);
DISPLAY 1.021277 (-2575 2650);
PAINT PURPLE (-2575 2650);
FORCENOTE
SPI_SWITCH_CS0_N
(-2700 3200) 0;
DISPLAY LEFT (-2700 3200);
DISPLAY 0.808511 (-2700 3200);
PAINT PURPLE (-2700 3200);
FORCENOTE
E#
(-7525 4575) 0;
DISPLAY LEFT (-7525 4575);
DISPLAY 1.021277 (-7525 4575);
PAINT PURPLE (-7525 4575);
FORCENOTE
X
(-7250 4475) 0;
DISPLAY LEFT (-7250 4475);
DISPLAY 1.021277 (-7250 4475);
PAINT PURPLE (-7250 4475);
FORCENOTE
(DEFAULT)
(-3325 2975) 0;
DISPLAY LEFT (-3325 2975);
DISPLAY 1.021277 (-3325 2975);
PAINT PURPLE (-3325 2975);
FORCENOTE
L
(-3200 2825) 0;
DISPLAY LEFT (-3200 2825);
DISPLAY 1.021277 (-3200 2825);
PAINT PURPLE (-3200 2825);
FORCENOTE
X
(-3200 2650) 0;
DISPLAY LEFT (-3200 2650);
DISPLAY 1.021277 (-3200 2650);
PAINT PURPLE (-3200 2650);
FORCENOTE
FUNCTION
(-6650 4575) 0;
DISPLAY LEFT (-6650 4575);
DISPLAY 1.021277 (-6650 4575);
PAINT PURPLE (-6650 4575);
FORCENOTE
S=0
(-6650 4375) 0;
DISPLAY LEFT (-6650 4375);
DISPLAY 1.021277 (-6650 4375);
PAINT PURPLE (-6650 4375);
FORCENOTE
S=1
(-6650 4275) 0;
DISPLAY LEFT (-6650 4275);
DISPLAY 1.021277 (-6650 4275);
PAINT PURPLE (-6650 4275);
FORCENOTE
H
(-7525 4475) 0;
DISPLAY LEFT (-7525 4475);
DISPLAY 1.021277 (-7525 4475);
PAINT PURPLE (-7525 4475);
FORCENOTE
L
(-7525 4375) 0;
DISPLAY LEFT (-7525 4375);
DISPLAY 1.021277 (-7525 4375);
PAINT PURPLE (-7525 4375);
FORCENOTE
L
(-7250 4375) 0;
DISPLAY LEFT (-7250 4375);
DISPLAY 1.021277 (-7250 4375);
PAINT PURPLE (-7250 4375);
FORCENOTE
H
(-7250 4275) 0;
DISPLAY LEFT (-7250 4275);
DISPLAY 1.021277 (-7250 4275);
PAINT PURPLE (-7250 4275);
FORCENOTE
HIZ
(-6925 4475) 0;
DISPLAY LEFT (-6925 4475);
DISPLAY 1.021277 (-6925 4475);
PAINT PURPLE (-6925 4475);
FORCENOTE
N
(-6900 4275) 0;
DISPLAY LEFT (-6900 4275);
DISPLAY 1.021277 (-6900 4275);
PAINT PURPLE (-6900 4275);
FORCENOTE
N
(-6900 4375) 0;
DISPLAY LEFT (-6900 4375);
DISPLAY 1.021277 (-6900 4375);
PAINT PURPLE (-6900 4375);
FORCENOTE
N
(-6875 4550) 0;
DISPLAY LEFT (-6875 4550);
DISPLAY 0.808511 (-6875 4550);
PAINT PURPLE (-6875 4550);
FORCENOTE
O
(-6850 4350) 0;
DISPLAY LEFT (-6850 4350);
DISPLAY 0.808511 (-6850 4350);
PAINT PURPLE (-6850 4350);
FORCENOTE
1
(-6850 4250) 0;
DISPLAY LEFT (-6850 4250);
DISPLAY 0.808511 (-6850 4250);
PAINT PURPLE (-6850 4250);
FORCENOTE
Y
(-6925 4575) 0;
DISPLAY LEFT (-6925 4575);
DISPLAY 1.021277 (-6925 4575);
PAINT PURPLE (-6925 4575);
FORCENOTE
H
(-3200 3050) 0;
DISPLAY LEFT (-3200 3050);
DISPLAY 1.021277 (-3200 3050);
PAINT PURPLE (-3200 3050);
FORCENOTE
L
(-2575 2825) 0;
DISPLAY LEFT (-2575 2825);
DISPLAY 1.021277 (-2575 2825);
PAINT PURPLE (-2575 2825);
FORCENOTE
L
(-2575 3000) 0;
DISPLAY LEFT (-2575 3000);
DISPLAY 1.021277 (-2575 3000);
PAINT PURPLE (-2575 3000);
FORCENOTE
BIOS
(-2025 3200) 0;
DISPLAY LEFT (-2025 3200);
DISPLAY 0.808511 (-2025 3200);
PAINT PURPLE (-2025 3200);
FORCENOTE
S
(-7250 4575) 0;
DISPLAY LEFT (-7250 4575);
DISPLAY 1.021277 (-7250 4575);
PAINT PURPLE (-7250 4575);
FORCENOTE
X
(-1975 2650) 0;
DISPLAY LEFT (-1975 2650);
DISPLAY 1.021277 (-1975 2650);
PAINT PURPLE (-1975 2650);
FORCENOTE
PRIMARY
(-2075 3050) 0;
DISPLAY LEFT (-2075 3050);
DISPLAY 1.021277 (-2075 3050);
PAINT PURPLE (-2075 3050);
FORCENOTE
(DEFAULT)
(-2075 2975) 0;
DISPLAY LEFT (-2075 2975);
DISPLAY 1.021277 (-2075 2975);
PAINT PURPLE (-2075 2975);
FORCENOTE
SECONDARY
(-2075 2825) 0;
DISPLAY LEFT (-2075 2825);
DISPLAY 1.021277 (-2075 2825);
PAINT PURPLE (-2075 2825);
FORCENOTE
DISABLE
(-6650 4475) 0;
DISPLAY LEFT (-6650 4475);
DISPLAY 1.021277 (-6650 4475);
PAINT PURPLE (-6650 4475);
FORCENOTE
$CDS_IMAGE|SPI.jpg|2222|2388
(-6775 1425) 0;
DISPLAY LEFT (-6775 1425);
QUIT
